G04 ================== begin FILE IDENTIFICATION RECORD ==================*
G04 Layout Name:  13919-sa.brd*
G04 Film Name:    SE_REF_L1*
G04 File Format:  Gerber RS274X*
G04 File Origin:  Cadence Allegro 16.5-S039*
G04 Origin Date:  Fri Nov 22 15:27:07 2013*
G04 *
G04 Layer:  BOARD GEOMETRY/SE_REF_L1_TBL*
G04 Layer:  BOARD GEOMETRY/SE_REF_L1_TOP*
G04 Layer:  BOARD GEOMETRY/PANEL_OUTLINE*
G04 *
G04 Offset:    (0.00 0.00)*
G04 Mirror:    No*
G04 Mode:      Positive*
G04 Rotation:  0*
G04 FullContactRelief:  No*
G04 UndefLineWidth:     6.00*
G04 ================== end FILE IDENTIFICATION RECORD ====================*
%FSLAX35Y35*MOIN*%
%IR0*IPPOS*OFA0.00000B0.00000*MIA0B0*SFA1.00000B1.00000*%
%ADD10C,.02*%
%ADD11C,.006*%
%ADD12C,.00425*%
G75*
%LPD*%
G75*
G54D10*
G01X825891Y587689D02*
X1333391D01*
G01X825891Y656989D02*
Y587689D01*
G01Y622339D02*
X1333391D01*
G01X825891Y656989D02*
X1333391D01*
G01X1000891D02*
Y587689D01*
G01X1228391Y656989D02*
Y587689D01*
G01X1333391Y656989D02*
Y587689D01*
G54D11*
G01X-14021Y-32800D02*
Y-50300D01*
G01X-19043Y-32800D02*
X-8999D01*
G01X-233Y-50300D02*
Y-32800D01*
G01Y-41258D02*
X859Y-39800D01*
X1951Y-38925D01*
X3697Y-38634D01*
X5007Y-38925D01*
X6536Y-40092D01*
X7191Y-41842D01*
Y-50300D01*
G01X20979Y-38634D02*
Y-50300D01*
G01Y-33967D02*
X20542Y-33675D01*
Y-33092D01*
X20979Y-32800D01*
X21416Y-33092D01*
Y-33675D01*
X20979Y-33967D01*
G01X35204Y-48259D02*
X36296Y-49425D01*
X37824Y-50300D01*
X39134D01*
X40444Y-49717D01*
X41317Y-48842D01*
X41754Y-47676D01*
X41536Y-45925D01*
X40662Y-45050D01*
X36732Y-43300D01*
X35859Y-41258D01*
X36296Y-39800D01*
X37169Y-38925D01*
X38479Y-38634D01*
X39789Y-38925D01*
X41099Y-39800D01*
G01X70422Y-54675D02*
X71951Y-55842D01*
X73697Y-56133D01*
X75225Y-55842D01*
X76536Y-54384D01*
X77409Y-52342D01*
Y-38634D01*
G01Y-40967D02*
X76536Y-39800D01*
X75225Y-38925D01*
X73697Y-38634D01*
X71951Y-39217D01*
X70859Y-40383D01*
X69985Y-42425D01*
X69549Y-44467D01*
X69767Y-46217D01*
X70641Y-48259D01*
X71951Y-49717D01*
X73697Y-50300D01*
X75007Y-50008D01*
X76536Y-48842D01*
X77409Y-47676D01*
G01X87704Y-42425D02*
X94691D01*
X94036Y-40383D01*
X92944Y-39217D01*
X91416Y-38634D01*
X89887Y-38925D01*
X88577Y-39800D01*
X87704Y-41842D01*
X87267Y-43592D01*
Y-45342D01*
X87704Y-47092D01*
X88796Y-48842D01*
X90106Y-50008D01*
X91634Y-50300D01*
X93162Y-49717D01*
X94691Y-47967D01*
G01X105422Y-50300D02*
Y-38634D01*
G01Y-40967D02*
X106514Y-39800D01*
X107606Y-38925D01*
X109134Y-38634D01*
X110225Y-38925D01*
X111536Y-39800D01*
G01X122049Y-50300D02*
Y-32800D01*
G01Y-41550D02*
X123141Y-39800D01*
X124451Y-38925D01*
X125761Y-38634D01*
X127725Y-39217D01*
X129036Y-40383D01*
X129909Y-42425D01*
Y-44758D01*
X129472Y-47092D01*
X128599Y-48842D01*
X127071Y-50008D01*
X125761Y-50300D01*
X124451Y-50008D01*
X123141Y-49134D01*
X122049Y-47676D01*
G01X140204Y-42425D02*
X147191D01*
X146536Y-40383D01*
X145444Y-39217D01*
X143916Y-38634D01*
X142387Y-38925D01*
X141077Y-39800D01*
X140204Y-41842D01*
X139767Y-43592D01*
Y-45342D01*
X140204Y-47092D01*
X141296Y-48842D01*
X142606Y-50008D01*
X144134Y-50300D01*
X145662Y-49717D01*
X147191Y-47967D01*
G01X157922Y-50300D02*
Y-38634D01*
G01Y-40967D02*
X159014Y-39800D01*
X160106Y-38925D01*
X161634Y-38634D01*
X162725Y-38925D01*
X164036Y-39800D01*
G01X195979Y-38634D02*
Y-50300D01*
G01Y-33967D02*
X195542Y-33675D01*
Y-33092D01*
X195979Y-32800D01*
X196416Y-33092D01*
Y-33675D01*
X195979Y-33967D01*
G01X210204Y-48259D02*
X211296Y-49425D01*
X212824Y-50300D01*
X214134D01*
X215444Y-49717D01*
X216317Y-48842D01*
X216754Y-47676D01*
X216536Y-45925D01*
X215662Y-45050D01*
X211732Y-43300D01*
X210859Y-41258D01*
X211296Y-39800D01*
X212169Y-38925D01*
X213479Y-38634D01*
X214789Y-38925D01*
X216099Y-39800D01*
G01X244985Y-54675D02*
X246514Y-55842D01*
X247824Y-56133D01*
X249571Y-55550D01*
X250881Y-54092D01*
X251536Y-51466D01*
Y-38634D01*
G01Y-33967D02*
X251099Y-33675D01*
Y-33092D01*
X251536Y-32800D01*
X251972Y-33092D01*
Y-33675D01*
X251536Y-33967D01*
G01X262267Y-38634D02*
Y-46800D01*
X263141Y-48842D01*
X264451Y-50008D01*
X265979Y-50300D01*
X267507Y-50008D01*
X268817Y-48842D01*
X269691Y-46800D01*
G01Y-50300D02*
Y-38634D01*
G01X280204Y-48259D02*
X281296Y-49425D01*
X282824Y-50300D01*
X284134D01*
X285444Y-49717D01*
X286317Y-48842D01*
X286754Y-47676D01*
X286536Y-45925D01*
X285662Y-45050D01*
X281732Y-43300D01*
X280859Y-41258D01*
X281296Y-39800D01*
X282169Y-38925D01*
X283479Y-38634D01*
X284789Y-38925D01*
X286099Y-39800D01*
G01X300979Y-32800D02*
Y-50300D01*
G01X297922Y-38634D02*
X304036D01*
G01X334669Y-50300D02*
Y-35425D01*
X335106Y-33967D01*
X335979Y-33092D01*
X337289Y-32800D01*
X338599Y-33383D01*
X339254Y-34842D01*
G01X336634Y-39800D02*
X332267D01*
G01X353479Y-50300D02*
X352169Y-50008D01*
X350859Y-48842D01*
X349985Y-46800D01*
X349549Y-44467D01*
X349985Y-42133D01*
X350859Y-40092D01*
X352169Y-38925D01*
X353479Y-38634D01*
X354789Y-38925D01*
X356099Y-40092D01*
X356972Y-42133D01*
X357191Y-44467D01*
X356972Y-46800D01*
X356099Y-48842D01*
X354789Y-50008D01*
X353479Y-50300D01*
G01X367922D02*
Y-38634D01*
G01Y-40967D02*
X369014Y-39800D01*
X370106Y-38925D01*
X371634Y-38634D01*
X372725Y-38925D01*
X374036Y-39800D01*
G01X401394Y-55550D02*
X402704Y-56133D01*
X404451Y-55550D01*
X405542Y-54384D01*
X406416Y-52925D01*
X407725Y-48259D01*
X410564Y-38634D01*
G01X403577D02*
X407725Y-48259D01*
G01X423479Y-50300D02*
X422169Y-50008D01*
X420859Y-48842D01*
X419985Y-46800D01*
X419549Y-44467D01*
X419985Y-42133D01*
X420859Y-40092D01*
X422169Y-38925D01*
X423479Y-38634D01*
X424789Y-38925D01*
X426099Y-40092D01*
X426972Y-42133D01*
X427191Y-44467D01*
X426972Y-46800D01*
X426099Y-48842D01*
X424789Y-50008D01*
X423479Y-50300D01*
G01X437267Y-38634D02*
Y-46800D01*
X438141Y-48842D01*
X439451Y-50008D01*
X440979Y-50300D01*
X442507Y-50008D01*
X443817Y-48842D01*
X444691Y-46800D01*
G01Y-50300D02*
Y-38634D01*
G01X455422Y-50300D02*
Y-38634D01*
G01Y-40967D02*
X456514Y-39800D01*
X457606Y-38925D01*
X459134Y-38634D01*
X460225Y-38925D01*
X461536Y-39800D01*
G01X490422Y-50300D02*
Y-38634D01*
G01Y-40967D02*
X491514Y-39800D01*
X492606Y-38925D01*
X494134Y-38634D01*
X495225Y-38925D01*
X496536Y-39800D01*
G01X507704Y-42425D02*
X514691D01*
X514036Y-40383D01*
X512944Y-39217D01*
X511416Y-38634D01*
X509887Y-38925D01*
X508577Y-39800D01*
X507704Y-41842D01*
X507267Y-43592D01*
Y-45342D01*
X507704Y-47092D01*
X508796Y-48842D01*
X510106Y-50008D01*
X511634Y-50300D01*
X513162Y-49717D01*
X514691Y-47967D01*
G01X527169Y-50300D02*
Y-35425D01*
X527606Y-33967D01*
X528479Y-33092D01*
X529789Y-32800D01*
X531099Y-33383D01*
X531754Y-34842D01*
G01X529134Y-39800D02*
X524767D01*
G01X542704Y-42425D02*
X549691D01*
X549036Y-40383D01*
X547944Y-39217D01*
X546416Y-38634D01*
X544887Y-38925D01*
X543577Y-39800D01*
X542704Y-41842D01*
X542267Y-43592D01*
Y-45342D01*
X542704Y-47092D01*
X543796Y-48842D01*
X545106Y-50008D01*
X546634Y-50300D01*
X548162Y-49717D01*
X549691Y-47967D01*
G01X560422Y-50300D02*
Y-38634D01*
G01Y-40967D02*
X561514Y-39800D01*
X562606Y-38925D01*
X564134Y-38634D01*
X565225Y-38925D01*
X566536Y-39800D01*
G01X577704Y-42425D02*
X584691D01*
X584036Y-40383D01*
X582944Y-39217D01*
X581416Y-38634D01*
X579887Y-38925D01*
X578577Y-39800D01*
X577704Y-41842D01*
X577267Y-43592D01*
Y-45342D01*
X577704Y-47092D01*
X578796Y-48842D01*
X580106Y-50008D01*
X581634Y-50300D01*
X583162Y-49717D01*
X584691Y-47967D01*
G01X594767Y-50300D02*
Y-38634D01*
G01Y-41550D02*
X595641Y-40092D01*
X596951Y-38925D01*
X598697Y-38634D01*
X600225Y-38925D01*
X601536Y-40092D01*
X602191Y-42133D01*
Y-50300D01*
G01X619472Y-40092D02*
X617944Y-38925D01*
X616634Y-38634D01*
X614887Y-39217D01*
X613577Y-40383D01*
X612704Y-42425D01*
X612485Y-44467D01*
X612704Y-46509D01*
X613577Y-48259D01*
X614887Y-49717D01*
X616634Y-50300D01*
X618162Y-49717D01*
X619472Y-48550D01*
G01X630204Y-42425D02*
X637191D01*
X636536Y-40383D01*
X635444Y-39217D01*
X633916Y-38634D01*
X632387Y-38925D01*
X631077Y-39800D01*
X630204Y-41842D01*
X629767Y-43592D01*
Y-45342D01*
X630204Y-47092D01*
X631296Y-48842D01*
X632606Y-50008D01*
X634134Y-50300D01*
X635662Y-49717D01*
X637191Y-47967D01*
G01X668479Y-32800D02*
Y-50300D01*
G01X665422Y-38634D02*
X671536D01*
G01X685979Y-50300D02*
X684669Y-50008D01*
X683359Y-48842D01*
X682485Y-46800D01*
X682049Y-44467D01*
X682485Y-42133D01*
X683359Y-40092D01*
X684669Y-38925D01*
X685979Y-38634D01*
X687289Y-38925D01*
X688599Y-40092D01*
X689472Y-42133D01*
X689691Y-44467D01*
X689472Y-46800D01*
X688599Y-48842D01*
X687289Y-50008D01*
X685979Y-50300D01*
G01X719669D02*
Y-35425D01*
X720106Y-33967D01*
X720979Y-33092D01*
X722289Y-32800D01*
X723599Y-33383D01*
X724254Y-34842D01*
G01X721634Y-39800D02*
X717267D01*
G01X738479Y-38634D02*
Y-50300D01*
G01Y-33967D02*
X738042Y-33675D01*
Y-33092D01*
X738479Y-32800D01*
X738916Y-33092D01*
Y-33675D01*
X738479Y-33967D01*
G01X752267Y-50300D02*
Y-38634D01*
G01Y-41550D02*
X753141Y-40092D01*
X754451Y-38925D01*
X756197Y-38634D01*
X757725Y-38925D01*
X759036Y-40092D01*
X759691Y-42133D01*
Y-50300D01*
G01X777409Y-32800D02*
Y-50300D01*
G01Y-47676D02*
X776536Y-49134D01*
X775225Y-50008D01*
X773697Y-50300D01*
X771951Y-49717D01*
X770641Y-48259D01*
X769767Y-46509D01*
X769549Y-44467D01*
X769767Y-42425D01*
X770641Y-40675D01*
X771951Y-39217D01*
X773697Y-38634D01*
X775225Y-38925D01*
X776317Y-39509D01*
X777409Y-40675D01*
G01X808479Y-32800D02*
Y-50300D01*
G01X805422Y-38634D02*
X811536D01*
G01X822267Y-50300D02*
Y-32800D01*
G01Y-41258D02*
X823359Y-39800D01*
X824451Y-38925D01*
X826197Y-38634D01*
X827507Y-38925D01*
X829036Y-40092D01*
X829691Y-41842D01*
Y-50300D01*
G01X840204Y-42425D02*
X847191D01*
X846536Y-40383D01*
X845444Y-39217D01*
X843916Y-38634D01*
X842387Y-38925D01*
X841077Y-39800D01*
X840204Y-41842D01*
X839767Y-43592D01*
Y-45342D01*
X840204Y-47092D01*
X841296Y-48842D01*
X842606Y-50008D01*
X844134Y-50300D01*
X845662Y-49717D01*
X847191Y-47967D01*
G01X873894D02*
X875641Y-49425D01*
X877606Y-50300D01*
X879352D01*
X881099Y-49425D01*
X882409Y-47967D01*
X883064Y-45925D01*
X882627Y-43884D01*
X881536Y-42133D01*
X879571Y-40967D01*
X876951Y-40383D01*
X875422Y-39217D01*
X874767Y-37175D01*
X875204Y-35133D01*
X876296Y-33675D01*
X877824Y-32800D01*
X879352D01*
X880881Y-33383D01*
X882191Y-34842D01*
G01X900346Y-50300D02*
X891612D01*
Y-32800D01*
X900346D01*
G01X896852Y-41258D02*
X891612D01*
G01X930979Y-38634D02*
Y-50300D01*
G01Y-33967D02*
X930542Y-33675D01*
Y-33092D01*
X930979Y-32800D01*
X931416Y-33092D01*
Y-33675D01*
X930979Y-33967D01*
G01X941929Y-50300D02*
Y-38634D01*
G01Y-41842D02*
X942584Y-40383D01*
X943676Y-39217D01*
X945204Y-38634D01*
X946732Y-39217D01*
X947824Y-40383D01*
X948479Y-41842D01*
Y-50300D01*
G01Y-41842D02*
X949134Y-40383D01*
X950225Y-39217D01*
X951754Y-38634D01*
X953282Y-39217D01*
X954374Y-40383D01*
X955029Y-42133D01*
Y-50300D01*
G01X962049Y-56133D02*
Y-38634D01*
G01Y-41258D02*
X963141Y-39800D01*
X964232Y-38925D01*
X965979Y-38634D01*
X967507Y-38925D01*
X969036Y-40383D01*
X969691Y-42425D01*
X969909Y-44467D01*
X969691Y-46509D01*
X969036Y-48550D01*
X967725Y-49717D01*
X965979Y-50300D01*
X964451Y-50008D01*
X962922Y-49134D01*
X962049Y-47967D01*
G01X980204Y-42425D02*
X987191D01*
X986536Y-40383D01*
X985444Y-39217D01*
X983916Y-38634D01*
X982387Y-38925D01*
X981077Y-39800D01*
X980204Y-41842D01*
X979767Y-43592D01*
Y-45342D01*
X980204Y-47092D01*
X981296Y-48842D01*
X982606Y-50008D01*
X984134Y-50300D01*
X985662Y-49717D01*
X987191Y-47967D01*
G01X1004909Y-32800D02*
Y-50300D01*
G01Y-47676D02*
X1004036Y-49134D01*
X1002725Y-50008D01*
X1001197Y-50300D01*
X999451Y-49717D01*
X998141Y-48259D01*
X997267Y-46509D01*
X997049Y-44467D01*
X997267Y-42425D01*
X998141Y-40675D01*
X999451Y-39217D01*
X1001197Y-38634D01*
X1002725Y-38925D01*
X1003817Y-39509D01*
X1004909Y-40675D01*
G01X1022409Y-50300D02*
Y-38634D01*
G01Y-40675D02*
X1021536Y-39509D01*
X1020225Y-38925D01*
X1018697Y-38634D01*
X1017169Y-39217D01*
X1015859Y-40383D01*
X1014985Y-42133D01*
X1014549Y-44467D01*
X1014985Y-46800D01*
X1015859Y-48550D01*
X1017169Y-49717D01*
X1018697Y-50300D01*
X1020225Y-50008D01*
X1021536Y-49134D01*
X1022409Y-47967D01*
G01X1032267Y-50300D02*
Y-38634D01*
G01Y-41550D02*
X1033141Y-40092D01*
X1034451Y-38925D01*
X1036197Y-38634D01*
X1037725Y-38925D01*
X1039036Y-40092D01*
X1039691Y-42133D01*
Y-50300D01*
G01X1056972Y-40092D02*
X1055444Y-38925D01*
X1054134Y-38634D01*
X1052387Y-39217D01*
X1051077Y-40383D01*
X1050204Y-42425D01*
X1049985Y-44467D01*
X1050204Y-46509D01*
X1051077Y-48259D01*
X1052387Y-49717D01*
X1054134Y-50300D01*
X1055662Y-49717D01*
X1056972Y-48550D01*
G01X1067704Y-42425D02*
X1074691D01*
X1074036Y-40383D01*
X1072944Y-39217D01*
X1071416Y-38634D01*
X1069887Y-38925D01*
X1068577Y-39800D01*
X1067704Y-41842D01*
X1067267Y-43592D01*
Y-45342D01*
X1067704Y-47092D01*
X1068796Y-48842D01*
X1070106Y-50008D01*
X1071634Y-50300D01*
X1073162Y-49717D01*
X1074691Y-47967D01*
G01X1105979Y-32800D02*
Y-50300D01*
G01X1102922Y-38634D02*
X1109036D01*
G01X1120422Y-50300D02*
Y-38634D01*
G01Y-40967D02*
X1121514Y-39800D01*
X1122606Y-38925D01*
X1124134Y-38634D01*
X1125225Y-38925D01*
X1126536Y-39800D01*
G01X1144909Y-50300D02*
Y-38634D01*
G01Y-40675D02*
X1144036Y-39509D01*
X1142725Y-38925D01*
X1141197Y-38634D01*
X1139669Y-39217D01*
X1138359Y-40383D01*
X1137485Y-42133D01*
X1137049Y-44467D01*
X1137485Y-46800D01*
X1138359Y-48550D01*
X1139669Y-49717D01*
X1141197Y-50300D01*
X1142725Y-50008D01*
X1144036Y-49134D01*
X1144909Y-47967D01*
G01X1161972Y-40092D02*
X1160444Y-38925D01*
X1159134Y-38634D01*
X1157387Y-39217D01*
X1156077Y-40383D01*
X1155204Y-42425D01*
X1154985Y-44467D01*
X1155204Y-46509D01*
X1156077Y-48259D01*
X1157387Y-49717D01*
X1159134Y-50300D01*
X1160662Y-49717D01*
X1161972Y-48550D01*
G01X1172704Y-42425D02*
X1179691D01*
X1179036Y-40383D01*
X1177944Y-39217D01*
X1176416Y-38634D01*
X1174887Y-38925D01*
X1173577Y-39800D01*
X1172704Y-41842D01*
X1172267Y-43592D01*
Y-45342D01*
X1172704Y-47092D01*
X1173796Y-48842D01*
X1175106Y-50008D01*
X1176634Y-50300D01*
X1178162Y-49717D01*
X1179691Y-47967D01*
G01X1190204Y-48259D02*
X1191296Y-49425D01*
X1192824Y-50300D01*
X1194134D01*
X1195444Y-49717D01*
X1196317Y-48842D01*
X1196754Y-47676D01*
X1196536Y-45925D01*
X1195662Y-45050D01*
X1191732Y-43300D01*
X1190859Y-41258D01*
X1191296Y-39800D01*
X1192169Y-38925D01*
X1193479Y-38634D01*
X1194789Y-38925D01*
X1196099Y-39800D01*
G01X1228479Y-38634D02*
Y-50300D01*
G01Y-33967D02*
X1228042Y-33675D01*
Y-33092D01*
X1228479Y-32800D01*
X1228916Y-33092D01*
Y-33675D01*
X1228479Y-33967D01*
G01X1242267Y-50300D02*
Y-38634D01*
G01Y-41550D02*
X1243141Y-40092D01*
X1244451Y-38925D01*
X1246197Y-38634D01*
X1247725Y-38925D01*
X1249036Y-40092D01*
X1249691Y-42133D01*
Y-50300D01*
G01X1280979D02*
Y-32800D01*
G01X1302409Y-50300D02*
Y-38634D01*
G01Y-40675D02*
X1301536Y-39509D01*
X1300225Y-38925D01*
X1298697Y-38634D01*
X1297169Y-39217D01*
X1295859Y-40383D01*
X1294985Y-42133D01*
X1294549Y-44467D01*
X1294985Y-46800D01*
X1295859Y-48550D01*
X1297169Y-49717D01*
X1298697Y-50300D01*
X1300225Y-50008D01*
X1301536Y-49134D01*
X1302409Y-47967D01*
G01X1311394Y-55550D02*
X1312704Y-56133D01*
X1314451Y-55550D01*
X1315542Y-54384D01*
X1316416Y-52925D01*
X1317725Y-48259D01*
X1320564Y-38634D01*
G01X1313577D02*
X1317725Y-48259D01*
G01X1330204Y-42425D02*
X1337191D01*
X1336536Y-40383D01*
X1335444Y-39217D01*
X1333916Y-38634D01*
X1332387Y-38925D01*
X1331077Y-39800D01*
X1330204Y-41842D01*
X1329767Y-43592D01*
Y-45342D01*
X1330204Y-47092D01*
X1331296Y-48842D01*
X1332606Y-50008D01*
X1334134Y-50300D01*
X1335662Y-49717D01*
X1337191Y-47967D01*
G01X1347922Y-50300D02*
Y-38634D01*
G01Y-40967D02*
X1349014Y-39800D01*
X1350106Y-38925D01*
X1351634Y-38634D01*
X1352725Y-38925D01*
X1354036Y-39800D01*
G01X1381612Y-32800D02*
Y-50300D01*
X1390346D01*
G01X1403479D02*
Y-32800D01*
X1400859Y-36300D01*
G01Y-50300D02*
X1406099D01*
G01X1420979Y-50883D02*
X1420542Y-50592D01*
Y-50008D01*
X1420979Y-49717D01*
X1421416Y-50008D01*
Y-50592D01*
X1420979Y-50883D01*
G01X827856Y669072D02*
X829603Y667614D01*
X831568Y666739D01*
X833314D01*
X835061Y667614D01*
X836371Y669072D01*
X837026Y671114D01*
X836589Y673155D01*
X835498Y674906D01*
X833533Y676072D01*
X830913Y676656D01*
X829384Y677822D01*
X828729Y679864D01*
X829166Y681906D01*
X830258Y683364D01*
X831786Y684239D01*
X833314D01*
X834843Y683656D01*
X836153Y682197D01*
G01X854308Y666739D02*
X845574D01*
Y684239D01*
X854308D01*
G01X850814Y675781D02*
X845574D01*
G01X882321Y684239D02*
X887561D01*
G01X884941D02*
Y666739D01*
G01X882321D02*
X887561D01*
G01X896764D02*
Y684239D01*
X902441Y669656D01*
X908118Y684239D01*
Y666739D01*
G01X915574D02*
Y684239D01*
X920814D01*
X922561Y683364D01*
X923871Y681322D01*
X924308Y678989D01*
X923871Y676656D01*
X922779Y674906D01*
X920814Y674030D01*
X915574D01*
G01X941808Y666739D02*
X933074D01*
Y684239D01*
X941808D01*
G01X938314Y675781D02*
X933074D01*
G01X950138Y666739D02*
Y684239D01*
X954504D01*
X956251Y683364D01*
X957561Y682197D01*
X958653Y680448D01*
X959526Y678405D01*
X959744Y675489D01*
X959526Y672572D01*
X958653Y670530D01*
X957561Y668780D01*
X956251Y667614D01*
X954504Y666739D01*
X950138D01*
G01X966982D02*
X972441Y684239D01*
X977900Y666739D01*
G01X975934Y672864D02*
X968947D01*
G01X984919Y666739D02*
Y684239D01*
X994963Y666739D01*
Y684239D01*
G01X1012244Y682780D02*
X1010934Y683656D01*
X1009406Y684239D01*
X1007659D01*
X1005694Y683364D01*
X1004166Y681906D01*
X1003074Y680155D01*
X1002201Y677239D01*
X1001982Y674614D01*
X1002419Y671989D01*
X1003074Y670239D01*
X1004384Y668489D01*
X1005913Y667322D01*
X1007441Y666739D01*
X1008969D01*
X1010498Y667322D01*
X1011808Y668197D01*
X1012900Y669363D01*
G01X1029308Y666739D02*
X1020574D01*
Y684239D01*
X1029308D01*
G01X1025814Y675781D02*
X1020574D01*
G01X1059941Y684239D02*
Y666739D01*
G01X1054919Y684239D02*
X1064963D01*
G01X1071982Y666739D02*
X1077441Y684239D01*
X1082900Y666739D01*
G01X1080934Y672864D02*
X1073947D01*
G01X1096687Y676072D02*
X1097561Y676947D01*
X1098216Y678405D01*
X1098653Y680448D01*
X1098216Y682197D01*
X1097343Y683364D01*
X1095814Y684239D01*
X1089919D01*
Y666739D01*
X1097124D01*
X1098653Y667905D01*
X1099526Y669656D01*
X1099963Y671697D01*
X1099526Y673739D01*
X1098216Y675489D01*
X1096687Y676072D01*
X1089919D01*
G01X1108074Y684239D02*
Y666739D01*
X1116808D01*
G01X1134308D02*
X1125574D01*
Y684239D01*
X1134308D01*
G01X1130814Y675781D02*
X1125574D01*
G01X1147441Y666156D02*
X1147004Y666447D01*
Y667031D01*
X1147441Y667322D01*
X1147878Y667031D01*
Y666447D01*
X1147441Y666156D01*
G01Y674030D02*
X1147004Y674322D01*
Y674906D01*
X1147441Y675197D01*
X1147878Y674906D01*
Y674322D01*
X1147441Y674030D01*
G01X1178074Y684239D02*
Y666739D01*
X1186808D01*
G01X1199941D02*
Y684239D01*
X1197321Y680739D01*
G01Y666739D02*
X1202561D01*
G01X849521Y649589D02*
X854761D01*
G01X852141D02*
Y632089D01*
G01X849521D02*
X854761D01*
G01X863964D02*
Y649589D01*
X869641Y635006D01*
X875318Y649589D01*
Y632089D01*
G01X882774D02*
Y649589D01*
X888014D01*
X889761Y648714D01*
X891071Y646672D01*
X891508Y644339D01*
X891071Y642006D01*
X889979Y640256D01*
X888014Y639380D01*
X882774D01*
G01X903549Y626256D02*
X901366Y629172D01*
X900274Y632089D01*
Y643755D01*
X901366Y646672D01*
X903549Y649589D01*
G01X922141Y632089D02*
X920394Y632381D01*
X918866Y633547D01*
X917556Y635297D01*
X916682Y637339D01*
X916246Y639672D01*
Y642006D01*
X916682Y644339D01*
X917556Y646381D01*
X918866Y648130D01*
X920394Y649297D01*
X922141Y649589D01*
X923887Y649297D01*
X925416Y648130D01*
X926726Y646381D01*
X927600Y644339D01*
X928036Y642006D01*
Y639672D01*
X927600Y637339D01*
X926726Y635297D01*
X925416Y633547D01*
X923887Y632381D01*
X922141Y632089D01*
G01X935929D02*
Y649589D01*
G01Y641131D02*
X937021Y642589D01*
X938113Y643464D01*
X939859Y643755D01*
X941169Y643464D01*
X942698Y642297D01*
X943353Y640547D01*
Y632089D01*
G01X950591D02*
Y643755D01*
G01Y640547D02*
X951246Y642006D01*
X952338Y643172D01*
X953866Y643755D01*
X955394Y643172D01*
X956486Y642006D01*
X957141Y640547D01*
Y632089D01*
G01Y640547D02*
X957796Y642006D01*
X958887Y643172D01*
X960416Y643755D01*
X961944Y643172D01*
X963036Y642006D01*
X963691Y640256D01*
Y632089D01*
G01X975733Y626256D02*
X977916Y629172D01*
X979008Y632089D01*
Y643755D01*
X977916Y646672D01*
X975733Y649589D01*
G01X882338Y600063D02*
X883647Y598605D01*
X885176Y597731D01*
X887141Y597439D01*
X889106Y598022D01*
X890634Y599189D01*
X891726Y601230D01*
X891944Y603564D01*
X891508Y605897D01*
X890416Y607356D01*
X888887Y608522D01*
X887359Y608814D01*
X885831Y608522D01*
X883866Y607356D01*
X884521Y614939D01*
X890416D01*
G01X904641D02*
X902894Y614356D01*
X901584Y612897D01*
X900711Y611148D01*
X900056Y608814D01*
X899838Y606189D01*
X900056Y603564D01*
X900711Y601230D01*
X901584Y599480D01*
X902894Y598022D01*
X904641Y597439D01*
X906387Y598022D01*
X907698Y599480D01*
X908571Y601230D01*
X909226Y603564D01*
X909444Y606189D01*
X909226Y608814D01*
X908571Y611148D01*
X907698Y612897D01*
X906387Y614356D01*
X904641Y614939D01*
G01X922141Y596856D02*
X921704Y597147D01*
Y597731D01*
X922141Y598022D01*
X922578Y597731D01*
Y597147D01*
X922141Y596856D01*
G01X939641Y614939D02*
X937894Y614356D01*
X936584Y612897D01*
X935711Y611148D01*
X935056Y608814D01*
X934838Y606189D01*
X935056Y603564D01*
X935711Y601230D01*
X936584Y599480D01*
X937894Y598022D01*
X939641Y597439D01*
X941387Y598022D01*
X942698Y599480D01*
X943571Y601230D01*
X944226Y603564D01*
X944444Y606189D01*
X944226Y608814D01*
X943571Y611148D01*
X942698Y612897D01*
X941387Y614356D01*
X939641Y614939D01*
G01X1020591Y649589D02*
X1023647Y632089D01*
X1027141Y649589D01*
X1030634Y632089D01*
X1033691Y649589D01*
G01X1042021D02*
X1047261D01*
G01X1044641D02*
Y632089D01*
G01X1042021D02*
X1047261D01*
G01X1057338D02*
Y649589D01*
X1061704D01*
X1063451Y648714D01*
X1064761Y647547D01*
X1065853Y645798D01*
X1066726Y643755D01*
X1066944Y640839D01*
X1066726Y637922D01*
X1065853Y635880D01*
X1064761Y634130D01*
X1063451Y632964D01*
X1061704Y632089D01*
X1057338D01*
G01X1079641Y649589D02*
Y632089D01*
G01X1074619Y649589D02*
X1084663D01*
G01X1092556Y632089D02*
Y649589D01*
G01X1101726D02*
Y632089D01*
G01Y640839D02*
X1092556D01*
G01X1113549Y626256D02*
X1111366Y629172D01*
X1110274Y632089D01*
Y643755D01*
X1111366Y646672D01*
X1113549Y649589D01*
G01X1125591Y632089D02*
Y643755D01*
G01Y640547D02*
X1126246Y642006D01*
X1127338Y643172D01*
X1128866Y643755D01*
X1130394Y643172D01*
X1131486Y642006D01*
X1132141Y640547D01*
Y632089D01*
G01Y640547D02*
X1132796Y642006D01*
X1133887Y643172D01*
X1135416Y643755D01*
X1136944Y643172D01*
X1138036Y642006D01*
X1138691Y640256D01*
Y632089D01*
G01X1149641Y643755D02*
Y632089D01*
G01Y648422D02*
X1149204Y648714D01*
Y649297D01*
X1149641Y649589D01*
X1150078Y649297D01*
Y648714D01*
X1149641Y648422D01*
G01X1167141Y632089D02*
Y649589D01*
G01X1181366Y634130D02*
X1182458Y632964D01*
X1183986Y632089D01*
X1185296D01*
X1186606Y632672D01*
X1187479Y633547D01*
X1187916Y634713D01*
X1187698Y636464D01*
X1186824Y637339D01*
X1182894Y639089D01*
X1182021Y641131D01*
X1182458Y642589D01*
X1183331Y643464D01*
X1184641Y643755D01*
X1185951Y643464D01*
X1187261Y642589D01*
G01X1203233Y626256D02*
X1205416Y629172D01*
X1206508Y632089D01*
Y643755D01*
X1205416Y646672D01*
X1203233Y649589D01*
G01X1091011Y597439D02*
Y614939D01*
X1082932Y602397D01*
X1093850D01*
G01X1105891Y596856D02*
X1105454Y597147D01*
Y597731D01*
X1105891Y598022D01*
X1106328Y597731D01*
Y597147D01*
X1105891Y596856D01*
G01X1119243Y612022D02*
X1120553Y613772D01*
X1122081Y614647D01*
X1123828Y614939D01*
X1126011Y614356D01*
X1127539Y612897D01*
X1127976Y611148D01*
X1127758Y609397D01*
X1126884Y607939D01*
X1122518Y605022D01*
X1120553Y602981D01*
X1119243Y600063D01*
X1118806Y597439D01*
X1127976D01*
G01X1136088Y600063D02*
X1137397Y598605D01*
X1138926Y597731D01*
X1140891Y597439D01*
X1142856Y598022D01*
X1144384Y599189D01*
X1145476Y601230D01*
X1145694Y603564D01*
X1145258Y605897D01*
X1144166Y607356D01*
X1142637Y608522D01*
X1141109Y608814D01*
X1139581Y608522D01*
X1137616Y607356D01*
X1138271Y614939D01*
X1144166D01*
G01X1254641Y649589D02*
Y632089D01*
G01X1249619Y649589D02*
X1259663D01*
G01X1272141Y632089D02*
Y639964D01*
X1267774Y649589D01*
G01X1276508D02*
X1272141Y639964D01*
G01X1285274Y632089D02*
Y649589D01*
X1290514D01*
X1292261Y648714D01*
X1293571Y646672D01*
X1294008Y644339D01*
X1293571Y642006D01*
X1292479Y640256D01*
X1290514Y639380D01*
X1285274D01*
G01X1311508Y632089D02*
X1302774D01*
Y649589D01*
X1311508D01*
G01X1308014Y641131D02*
X1302774D01*
G01X1267556Y599772D02*
X1269303Y598314D01*
X1271268Y597439D01*
X1273014D01*
X1274761Y598314D01*
X1276071Y599772D01*
X1276726Y601814D01*
X1276289Y603855D01*
X1275198Y605606D01*
X1273233Y606772D01*
X1270613Y607356D01*
X1269084Y608522D01*
X1268429Y610564D01*
X1268866Y612606D01*
X1269958Y614064D01*
X1271486Y614939D01*
X1273014D01*
X1274543Y614356D01*
X1275853Y612897D01*
G01X1294008Y597439D02*
X1285274D01*
Y614939D01*
X1294008D01*
G01X1290514Y606481D02*
X1285274D01*
G01X1459941Y574455D02*
Y562789D01*
G01Y579122D02*
X1459504Y579414D01*
Y579997D01*
X1459941Y580289D01*
X1460378Y579997D01*
Y579414D01*
X1459941Y579122D01*
G01X1473729Y562789D02*
Y574455D01*
G01Y571539D02*
X1474603Y572997D01*
X1475913Y574164D01*
X1477659Y574455D01*
X1479187Y574164D01*
X1480498Y572997D01*
X1481153Y570956D01*
Y562789D01*
G01X1491666Y564830D02*
X1492758Y563664D01*
X1494286Y562789D01*
X1495596D01*
X1496906Y563372D01*
X1497779Y564247D01*
X1498216Y565413D01*
X1497998Y567164D01*
X1497124Y568039D01*
X1493194Y569789D01*
X1492321Y571831D01*
X1492758Y573289D01*
X1493631Y574164D01*
X1494941Y574455D01*
X1496251Y574164D01*
X1497561Y573289D01*
G01X1512441Y574455D02*
Y562789D01*
G01Y579122D02*
X1512004Y579414D01*
Y579997D01*
X1512441Y580289D01*
X1512878Y579997D01*
Y579414D01*
X1512441Y579122D01*
G01X1533871Y580289D02*
Y562789D01*
G01Y565413D02*
X1532998Y563955D01*
X1531687Y563081D01*
X1530159Y562789D01*
X1528413Y563372D01*
X1527103Y564830D01*
X1526229Y566580D01*
X1526011Y568622D01*
X1526229Y570664D01*
X1527103Y572414D01*
X1528413Y573872D01*
X1530159Y574455D01*
X1531687Y574164D01*
X1532779Y573580D01*
X1533871Y572414D01*
G01X1544166Y570664D02*
X1551153D01*
X1550498Y572706D01*
X1549406Y573872D01*
X1547878Y574455D01*
X1546349Y574164D01*
X1545039Y573289D01*
X1544166Y571247D01*
X1543729Y569497D01*
Y567747D01*
X1544166Y565997D01*
X1545258Y564247D01*
X1546568Y563081D01*
X1548096Y562789D01*
X1549624Y563372D01*
X1551153Y565122D01*
G01X1578511Y562789D02*
Y580289D01*
G01Y571539D02*
X1579603Y573289D01*
X1580913Y574164D01*
X1582223Y574455D01*
X1584187Y573872D01*
X1585498Y572706D01*
X1586371Y570664D01*
Y568331D01*
X1585934Y565997D01*
X1585061Y564247D01*
X1583533Y563081D01*
X1582223Y562789D01*
X1580913Y563081D01*
X1579603Y563955D01*
X1578511Y565413D01*
G01X1599941Y562789D02*
X1598631Y563081D01*
X1597321Y564247D01*
X1596447Y566289D01*
X1596011Y568622D01*
X1596447Y570956D01*
X1597321Y572997D01*
X1598631Y574164D01*
X1599941Y574455D01*
X1601251Y574164D01*
X1602561Y572997D01*
X1603434Y570956D01*
X1603653Y568622D01*
X1603434Y566289D01*
X1602561Y564247D01*
X1601251Y563081D01*
X1599941Y562789D01*
G01X1621371D02*
Y574455D01*
G01Y572414D02*
X1620498Y573580D01*
X1619187Y574164D01*
X1617659Y574455D01*
X1616131Y573872D01*
X1614821Y572706D01*
X1613947Y570956D01*
X1613511Y568622D01*
X1613947Y566289D01*
X1614821Y564539D01*
X1616131Y563372D01*
X1617659Y562789D01*
X1619187Y563081D01*
X1620498Y563955D01*
X1621371Y565122D01*
G01X1631884Y562789D02*
Y574455D01*
G01Y572122D02*
X1632976Y573289D01*
X1634068Y574164D01*
X1635596Y574455D01*
X1636687Y574164D01*
X1637998Y573289D01*
G01X1656371Y580289D02*
Y562789D01*
G01Y565413D02*
X1655498Y563955D01*
X1654187Y563081D01*
X1652659Y562789D01*
X1650913Y563372D01*
X1649603Y564830D01*
X1648729Y566580D01*
X1648511Y568622D01*
X1648729Y570664D01*
X1649603Y572414D01*
X1650913Y573872D01*
X1652659Y574455D01*
X1654187Y574164D01*
X1655279Y573580D01*
X1656371Y572414D01*
G01X1687441Y562789D02*
X1686131Y563081D01*
X1684821Y564247D01*
X1683947Y566289D01*
X1683511Y568622D01*
X1683947Y570956D01*
X1684821Y572997D01*
X1686131Y574164D01*
X1687441Y574455D01*
X1688751Y574164D01*
X1690061Y572997D01*
X1690934Y570956D01*
X1691153Y568622D01*
X1690934Y566289D01*
X1690061Y564247D01*
X1688751Y563081D01*
X1687441Y562789D01*
G01X1701229Y574455D02*
Y566289D01*
X1702103Y564247D01*
X1703413Y563081D01*
X1704941Y562789D01*
X1706469Y563081D01*
X1707779Y564247D01*
X1708653Y566289D01*
G01Y562789D02*
Y574455D01*
G01X1722441Y580289D02*
Y562789D01*
G01X1719384Y574455D02*
X1725498D01*
G01X1739941Y562789D02*
Y580289D01*
G01X1757441Y574455D02*
Y562789D01*
G01Y579122D02*
X1757004Y579414D01*
Y579997D01*
X1757441Y580289D01*
X1757878Y579997D01*
Y579414D01*
X1757441Y579122D01*
G01X1771229Y562789D02*
Y574455D01*
G01Y571539D02*
X1772103Y572997D01*
X1773413Y574164D01*
X1775159Y574455D01*
X1776687Y574164D01*
X1777998Y572997D01*
X1778653Y570956D01*
Y562789D01*
G01X1789166Y570664D02*
X1796153D01*
X1795498Y572706D01*
X1794406Y573872D01*
X1792878Y574455D01*
X1791349Y574164D01*
X1790039Y573289D01*
X1789166Y571247D01*
X1788729Y569497D01*
Y567747D01*
X1789166Y565997D01*
X1790258Y564247D01*
X1791568Y563081D01*
X1793096Y562789D01*
X1794624Y563372D01*
X1796153Y565122D01*
G01X1809941Y562206D02*
X1809504Y562497D01*
Y563081D01*
X1809941Y563372D01*
X1810378Y563081D01*
Y562497D01*
X1809941Y562206D01*
G01X1385138Y631506D02*
X1394744Y644339D01*
G01X1389941Y646672D02*
Y629172D01*
G01X1394744Y631506D02*
X1385138Y644339D01*
G01X1383391Y637922D02*
X1396491D01*
G01X1422103D02*
X1427779D01*
G01X1455138Y632089D02*
Y649589D01*
X1459504D01*
X1461251Y648714D01*
X1462561Y647547D01*
X1463653Y645798D01*
X1464526Y643755D01*
X1464744Y640839D01*
X1464526Y637922D01*
X1463653Y635880D01*
X1462561Y634130D01*
X1461251Y632964D01*
X1459504Y632089D01*
X1455138D01*
G01X1474166Y639964D02*
X1481153D01*
X1480498Y642006D01*
X1479406Y643172D01*
X1477878Y643755D01*
X1476349Y643464D01*
X1475039Y642589D01*
X1474166Y640547D01*
X1473729Y638797D01*
Y637047D01*
X1474166Y635297D01*
X1475258Y633547D01*
X1476568Y632381D01*
X1478096Y632089D01*
X1479624Y632672D01*
X1481153Y634422D01*
G01X1491229Y632089D02*
Y643755D01*
G01Y640839D02*
X1492103Y642297D01*
X1493413Y643464D01*
X1495159Y643755D01*
X1496687Y643464D01*
X1497998Y642297D01*
X1498653Y640256D01*
Y632089D01*
G01X1512441D02*
X1511131Y632381D01*
X1509821Y633547D01*
X1508947Y635589D01*
X1508511Y637922D01*
X1508947Y640256D01*
X1509821Y642297D01*
X1511131Y643464D01*
X1512441Y643755D01*
X1513751Y643464D01*
X1515061Y642297D01*
X1515934Y640256D01*
X1516153Y637922D01*
X1515934Y635589D01*
X1515061Y633547D01*
X1513751Y632381D01*
X1512441Y632089D01*
G01X1529941Y649589D02*
Y632089D01*
G01X1526884Y643755D02*
X1532998D01*
G01X1544166Y639964D02*
X1551153D01*
X1550498Y642006D01*
X1549406Y643172D01*
X1547878Y643755D01*
X1546349Y643464D01*
X1545039Y642589D01*
X1544166Y640547D01*
X1543729Y638797D01*
Y637047D01*
X1544166Y635297D01*
X1545258Y633547D01*
X1546568Y632381D01*
X1548096Y632089D01*
X1549624Y632672D01*
X1551153Y634422D01*
G01X1561666Y634130D02*
X1562758Y632964D01*
X1564286Y632089D01*
X1565596D01*
X1566906Y632672D01*
X1567779Y633547D01*
X1568216Y634713D01*
X1567998Y636464D01*
X1567124Y637339D01*
X1563194Y639089D01*
X1562321Y641131D01*
X1562758Y642589D01*
X1563631Y643464D01*
X1564941Y643755D01*
X1566251Y643464D01*
X1567561Y642589D01*
G01X1599941Y649589D02*
Y632089D01*
G01X1596884Y643755D02*
X1602998D01*
G01X1613729Y632089D02*
Y649589D01*
G01Y641131D02*
X1614821Y642589D01*
X1615913Y643464D01*
X1617659Y643755D01*
X1618969Y643464D01*
X1620498Y642297D01*
X1621153Y640547D01*
Y632089D01*
G01X1638871D02*
Y643755D01*
G01Y641714D02*
X1637998Y642880D01*
X1636687Y643464D01*
X1635159Y643755D01*
X1633631Y643172D01*
X1632321Y642006D01*
X1631447Y640256D01*
X1631011Y637922D01*
X1631447Y635589D01*
X1632321Y633839D01*
X1633631Y632672D01*
X1635159Y632089D01*
X1636687Y632381D01*
X1637998Y633255D01*
X1638871Y634422D01*
G01X1652441Y649589D02*
Y632089D01*
G01X1649384Y643755D02*
X1655498D01*
G01X1680891Y649589D02*
X1683947Y632089D01*
X1687441Y649589D01*
X1690934Y632089D01*
X1693991Y649589D01*
G01X1702321D02*
X1707561D01*
G01X1704941D02*
Y632089D01*
G01X1702321D02*
X1707561D01*
G01X1717638D02*
Y649589D01*
X1722004D01*
X1723751Y648714D01*
X1725061Y647547D01*
X1726153Y645798D01*
X1727026Y643755D01*
X1727244Y640839D01*
X1727026Y637922D01*
X1726153Y635880D01*
X1725061Y634130D01*
X1723751Y632964D01*
X1722004Y632089D01*
X1717638D01*
G01X1739941Y649589D02*
Y632089D01*
G01X1734919Y649589D02*
X1744963D01*
G01X1752856Y632089D02*
Y649589D01*
G01X1762026D02*
Y632089D01*
G01Y640839D02*
X1752856D01*
G01X1459941Y609105D02*
Y597439D01*
G01Y613772D02*
X1459504Y614064D01*
Y614647D01*
X1459941Y614939D01*
X1460378Y614647D01*
Y614064D01*
X1459941Y613772D01*
G01X1474166Y599480D02*
X1475258Y598314D01*
X1476786Y597439D01*
X1478096D01*
X1479406Y598022D01*
X1480279Y598897D01*
X1480716Y600063D01*
X1480498Y601814D01*
X1479624Y602689D01*
X1475694Y604439D01*
X1474821Y606481D01*
X1475258Y607939D01*
X1476131Y608814D01*
X1477441Y609105D01*
X1478751Y608814D01*
X1480061Y607939D01*
G01X1507419Y597439D02*
Y614939D01*
X1517463Y597439D01*
Y614939D01*
G01X1529941Y597439D02*
X1528194Y597731D01*
X1526666Y598897D01*
X1525356Y600647D01*
X1524482Y602689D01*
X1524046Y605022D01*
Y607356D01*
X1524482Y609689D01*
X1525356Y611731D01*
X1526666Y613480D01*
X1528194Y614647D01*
X1529941Y614939D01*
X1531687Y614647D01*
X1533216Y613480D01*
X1534526Y611731D01*
X1535400Y609689D01*
X1535836Y607356D01*
Y605022D01*
X1535400Y602689D01*
X1534526Y600647D01*
X1533216Y598897D01*
X1531687Y597731D01*
X1529941Y597439D01*
G01X1547441Y614939D02*
Y597439D01*
G01X1542419Y614939D02*
X1552463D01*
G01X1578729Y609105D02*
Y600939D01*
X1579603Y598897D01*
X1580913Y597731D01*
X1582441Y597439D01*
X1583969Y597731D01*
X1585279Y598897D01*
X1586153Y600939D01*
G01Y597439D02*
Y609105D01*
G01X1596666Y599480D02*
X1597758Y598314D01*
X1599286Y597439D01*
X1600596D01*
X1601906Y598022D01*
X1602779Y598897D01*
X1603216Y600063D01*
X1602998Y601814D01*
X1602124Y602689D01*
X1598194Y604439D01*
X1597321Y606481D01*
X1597758Y607939D01*
X1598631Y608814D01*
X1599941Y609105D01*
X1601251Y608814D01*
X1602561Y607939D01*
G01X1614166Y605314D02*
X1621153D01*
X1620498Y607356D01*
X1619406Y608522D01*
X1617878Y609105D01*
X1616349Y608814D01*
X1615039Y607939D01*
X1614166Y605897D01*
X1613729Y604147D01*
Y602397D01*
X1614166Y600647D01*
X1615258Y598897D01*
X1616568Y597731D01*
X1618096Y597439D01*
X1619624Y598022D01*
X1621153Y599772D01*
G01X1638871Y614939D02*
Y597439D01*
G01Y600063D02*
X1637998Y598605D01*
X1636687Y597731D01*
X1635159Y597439D01*
X1633413Y598022D01*
X1632103Y599480D01*
X1631229Y601230D01*
X1631011Y603272D01*
X1631229Y605314D01*
X1632103Y607064D01*
X1633413Y608522D01*
X1635159Y609105D01*
X1636687Y608814D01*
X1637779Y608230D01*
X1638871Y607064D01*
G01X1669941Y609105D02*
Y597439D01*
G01Y613772D02*
X1669504Y614064D01*
Y614647D01*
X1669941Y614939D01*
X1670378Y614647D01*
Y614064D01*
X1669941Y613772D01*
G01X1683729Y597439D02*
Y609105D01*
G01Y606189D02*
X1684603Y607647D01*
X1685913Y608814D01*
X1687659Y609105D01*
X1689187Y608814D01*
X1690498Y607647D01*
X1691153Y605606D01*
Y597439D01*
G01X1722441Y614939D02*
Y597439D01*
G01X1719384Y609105D02*
X1725498D01*
G01X1736229Y597439D02*
Y614939D01*
G01Y606481D02*
X1737321Y607939D01*
X1738413Y608814D01*
X1740159Y609105D01*
X1741469Y608814D01*
X1742998Y607647D01*
X1743653Y605897D01*
Y597439D01*
G01X1757441Y609105D02*
Y597439D01*
G01Y613772D02*
X1757004Y614064D01*
Y614647D01*
X1757441Y614939D01*
X1757878Y614647D01*
Y614064D01*
X1757441Y613772D01*
G01X1771666Y599480D02*
X1772758Y598314D01*
X1774286Y597439D01*
X1775596D01*
X1776906Y598022D01*
X1777779Y598897D01*
X1778216Y600063D01*
X1777998Y601814D01*
X1777124Y602689D01*
X1773194Y604439D01*
X1772321Y606481D01*
X1772758Y607939D01*
X1773631Y608814D01*
X1774941Y609105D01*
X1776251Y608814D01*
X1777561Y607939D01*
G01X1809941Y597439D02*
Y614939D01*
G01X1831371Y597439D02*
Y609105D01*
G01Y607064D02*
X1830498Y608230D01*
X1829187Y608814D01*
X1827659Y609105D01*
X1826131Y608522D01*
X1824821Y607356D01*
X1823947Y605606D01*
X1823511Y603272D01*
X1823947Y600939D01*
X1824821Y599189D01*
X1826131Y598022D01*
X1827659Y597439D01*
X1829187Y597731D01*
X1830498Y598605D01*
X1831371Y599772D01*
G01X1840356Y592189D02*
X1841666Y591606D01*
X1843413Y592189D01*
X1844504Y593355D01*
X1845378Y594814D01*
X1846687Y599480D01*
X1849526Y609105D01*
G01X1842539D02*
X1846687Y599480D01*
G01X1859166Y605314D02*
X1866153D01*
X1865498Y607356D01*
X1864406Y608522D01*
X1862878Y609105D01*
X1861349Y608814D01*
X1860039Y607939D01*
X1859166Y605897D01*
X1858729Y604147D01*
Y602397D01*
X1859166Y600647D01*
X1860258Y598897D01*
X1861568Y597731D01*
X1863096Y597439D01*
X1864624Y598022D01*
X1866153Y599772D01*
G01X1876884Y597439D02*
Y609105D01*
G01Y606772D02*
X1877976Y607939D01*
X1879068Y608814D01*
X1880596Y609105D01*
X1881687Y608814D01*
X1882998Y607939D01*
G01X-20271Y15000D02*
Y676339D01*
G01Y15000D02*
G03X-5271Y0I15000J0D01*
G01Y691339D02*
G03X-20271Y676339I0J-15000D01*
G01X0Y37795D02*
G03X3937Y33858I3937J0D01*
G01X21063Y29921D02*
G03X17126Y33858I-3937J0D01*
G01X3937D02*
X17126D01*
G01X299409Y0D02*
X23031D01*
G01X21063Y1969D02*
X23031Y0D01*
G01X21063Y1969D02*
Y29921D01*
G01X0Y102756D02*
Y37795D01*
G01D02*
G03X-7874I-3937J0D01*
G01X3937Y25984D02*
X13189D01*
G01X-7874Y37795D02*
G03X3937Y25984I11811J0D01*
G01X13189Y0D02*
X-5271D01*
G01X13189Y25984D02*
Y0D01*
G01X3937Y106693D02*
G03X0Y102756I0J-3937D01*
G01X-7874Y68504D02*
G03X0I3937J0D01*
G01X-7874D02*
Y122737D01*
G01X0Y118504D02*
G03X3937Y114567I3937J0D01*
G01Y157382D02*
G03X0Y153445I0J-3937D01*
G01X17126Y157382D02*
G03X21063Y161319I0J3937D01*
G01X0Y118504D02*
Y153445D01*
G01X21063Y219292D02*
Y161319D01*
G01D02*
Y187402D01*
G01X143701Y114567D02*
X3937D01*
G01Y157382D02*
X17126D01*
G01X3937Y106693D02*
X143701D01*
G01X-7874Y153445D02*
Y157382D01*
G01Y153445D02*
G03X0I3937J0D01*
G01Y122737D02*
G03X-7874I-3937J0D01*
G01X-10433Y161070D02*
G03X-7874Y157382I3937J0D01*
G01X-10433Y265210D02*
Y161070D01*
G01X51378Y181496D02*
G03X47441Y177559I0J-3937D01*
G01Y165748D02*
G03X51378Y161811I3937J0D01*
G01X47441Y165748D02*
Y177559D01*
G01X23031Y221260D02*
X21063Y219292D01*
G01X23031Y221260D02*
X63189D01*
G01X0Y272835D02*
G03X3937Y268898I3937J0D01*
G01X21063Y264961D02*
G03X17126Y268898I-3937J0D01*
G01X3937D02*
X17126D01*
G01X299409Y235040D02*
X23031D01*
G01X21063Y237008D02*
X23031Y235040D01*
G01X21063Y237008D02*
Y264961D01*
G01X0Y337796D02*
Y272835D01*
G01D02*
G03X-7874I-3937J0D01*
G01Y268898D02*
G03X-10433Y265210I1378J-3688D01*
G01X-7874Y268898D02*
Y272835D01*
G01X3937Y341733D02*
G03X0Y337796I0J-3937D01*
G01X3937Y341733D02*
X143701D01*
G01X-7874Y303543D02*
Y357781D01*
G01Y303544D02*
G03X0I3937J0D01*
G01X47441Y400788D02*
G03X51378Y396851I3937J0D01*
G01X47441Y400788D02*
Y412599D01*
G01X0Y353544D02*
G03X3937Y349607I3937J0D01*
G01Y392422D02*
G03X0Y388485I0J-3937D01*
G01X17126Y392422D02*
G03X21063Y396359I0J3937D01*
G01X0Y353544D02*
Y388485D01*
G01X21063Y454331D02*
Y396359D01*
G01D02*
Y422441D01*
G01X143701Y349607D02*
X3937D01*
G01Y392422D02*
X17126D01*
G01X-7874Y388480D02*
Y392422D01*
G01Y388485D02*
G03X0I3937J0D01*
G01Y357776D02*
G03X-7874I-3937J0D01*
G01X-10433Y396110D02*
G03X-7874Y392422I3937J0D01*
G01X-10433Y500250D02*
Y396110D01*
G01X51378Y416536D02*
G03X47441Y412599I0J-3937D01*
G01X23031Y456300D02*
X21063Y454331D01*
G01X23031Y456300D02*
X63189D01*
G01X0Y507874D02*
G03X3937Y503937I3937J0D01*
G01X21063Y500000D02*
G03X17126Y503937I-3937J0D01*
G01X3937D02*
X17126D01*
G01X299409Y470079D02*
X23031D01*
G01X21063Y472048D02*
X23031Y470079D01*
G01X21063Y472048D02*
Y500000D01*
G01X0Y572835D02*
Y507874D01*
G01D02*
G03X-7874I-3937J0D01*
G01Y503937D02*
Y507880D01*
G01Y503937D02*
G03X-10433Y500250I1378J-3688D01*
G01X3937Y576772D02*
G03X0Y572835I0J-3937D01*
G01X3937Y576772D02*
X143701D01*
G01X0Y588583D02*
G03X3937Y584646I3937J0D01*
G01X0Y588583D02*
Y623524D01*
G01X143701Y584646D02*
X3937D01*
G01X-7874Y538578D02*
Y592823D01*
G01Y538583D02*
G03X0I3937J0D01*
G01X51378Y651576D02*
G03X47441Y647639I0J-3937D01*
G01Y635828D02*
G03X51378Y631891I3937J0D01*
G01X47441Y635828D02*
Y647639D01*
G01X3937Y627461D02*
G03X0Y623524I0J-3937D01*
G01X17126Y627461D02*
G03X21063Y631398I0J3937D01*
G01Y689371D02*
Y631398D01*
G01D02*
Y657481D01*
G01X3937Y627461D02*
X17126D01*
G01X1830Y651994D02*
G03I-4292J0D01*
G01X-7874Y623517D02*
Y623536D01*
G01X13189Y691339D02*
Y635335D01*
G01X3937D02*
X13189D01*
G01X3937D02*
G03X-7874Y623524I0J-11811D01*
G01D02*
G03X0I3937J0D01*
G01Y592816D02*
G03X-7874I-3937J0D01*
G01X23031Y691339D02*
X21063Y689371D01*
G01X23031Y691339D02*
X63189D01*
G01X13189D02*
X-5271D01*
G01X63189Y161811D02*
G03X67126Y165748I0J3937D01*
G01X73425D02*
G03X77362Y161811I3937J0D01*
G01X89173D02*
G03X93110Y165748I0J3937D01*
G01X99409D02*
G03X103346Y161811I3937J0D01*
G01X63189D02*
X51378D01*
G01X89173D02*
X77362D01*
G01X115157D02*
X103346D01*
G01X89173Y114567D02*
G03Y106693I0J-3937D01*
G01X58465D02*
G03Y114567I0J3937D01*
G01X67126Y177559D02*
G03X63189Y181496I-3937J0D01*
G01X77362D02*
G03X73425Y177559I0J-3937D01*
G01X93110D02*
G03X89173Y181496I-3937J0D01*
G01X103346D02*
G03X99409Y177559I0J-3937D01*
G01X67126D02*
Y165748D01*
G01X73425D02*
Y177559D01*
G01X93110D02*
Y165748D01*
G01X99409D02*
Y177559D01*
G01X103346Y181496D02*
X115157D01*
G01X77362D02*
X89173D01*
G01X51378D02*
X63189D01*
G01X65157Y191930D02*
G03X72638I3740J0D01*
G01X65157Y219292D02*
Y191930D01*
G01X74606Y221260D02*
X72638Y219292D01*
G01D02*
Y191930D01*
G01X65157Y219292D02*
X63189Y221260D01*
G01X74606D02*
X350984D01*
G01X89173Y349607D02*
G03Y341733I0J-3937D01*
G01X58465D02*
G03Y349607I0J3937D01*
G01X63189Y396851D02*
G03X67126Y400788I0J3937D01*
G01X73425D02*
G03X77362Y396851I3937J0D01*
G01X89173D02*
G03X93110Y400788I0J3937D01*
G01X99409D02*
G03X103346Y396851I3937J0D01*
G01X67126Y412599D02*
Y400788D01*
G01X73425D02*
Y412599D01*
G01X93110D02*
Y400788D01*
G01X99409D02*
Y412599D01*
G01X63189Y396851D02*
X51378D01*
G01X89173D02*
X77362D01*
G01X115157D02*
X103346D01*
G01X67126Y412599D02*
G03X63189Y416536I-3937J0D01*
G01X77362D02*
G03X73425Y412599I0J-3937D01*
G01X93110D02*
G03X89173Y416536I-3937J0D01*
G01X103346D02*
G03X99409Y412599I0J-3937D01*
G01X103346Y416536D02*
X115157D01*
G01X77362D02*
X89173D01*
G01X51378D02*
X63189D01*
G01X65157Y426969D02*
G03X72638I3740J0D01*
G01X65157Y454331D02*
Y426969D01*
G01X74606Y456300D02*
X72638Y454331D01*
G01D02*
Y426969D01*
G01X65157Y454331D02*
X63189Y456300D01*
G01X74606D02*
X350984D01*
G01X89173Y584646D02*
G03Y576772I0J-3937D01*
G01X58465D02*
G03Y584646I0J3937D01*
G01X67126Y647639D02*
G03X63189Y651576I-3937J0D01*
G01Y631891D02*
G03X67126Y635828I0J3937D01*
G01X73425D02*
G03X77362Y631891I3937J0D01*
G01Y651576D02*
G03X73425Y647639I0J-3937D01*
G01X93110D02*
G03X89173Y651576I-3937J0D01*
G01Y631891D02*
G03X93110Y635828I0J3937D01*
G01X103346Y651576D02*
G03X99409Y647639I0J-3937D01*
G01Y635828D02*
G03X103346Y631891I3937J0D01*
G01X67126Y647639D02*
Y635828D01*
G01X73425D02*
Y647639D01*
G01X93110D02*
Y635828D01*
G01X99409D02*
Y647639D01*
G01X63189Y631891D02*
X51378D01*
G01X89173D02*
X77362D01*
G01X115157D02*
X103346D01*
G01Y651576D02*
X115157D01*
G01X77362D02*
X89173D01*
G01X51378D02*
X63189D01*
G01X65157Y662009D02*
G03X72638I3740J0D01*
G01X65157Y689371D02*
Y662009D01*
G01X74606Y691339D02*
X72638Y689371D01*
G01D02*
Y662009D01*
G01X65157Y689371D02*
X63189Y691339D01*
G01X74606D02*
X350984D01*
G01X147638Y102756D02*
G03X151575Y98819I3937J0D01*
G01X147638Y102756D02*
G03X143701Y106693I-3937J0D01*
G01X147638Y102756D02*
G03X151575Y98819I3937J0D01*
G01X147638Y102756D02*
G03X143701Y106693I-3937J0D01*
G01X147638Y102756D02*
G03X151575Y98819I3937J0D01*
G01X147638Y102756D02*
G03X143701Y106693I-3937J0D01*
G01X151575Y98819D02*
X222441D01*
G01X115157Y161811D02*
G03X119094Y165748I0J3937D01*
G01X151575Y122441D02*
G03X147638Y118504I0J-3937D01*
G01X143701Y114567D02*
G03X147638Y118504I0J3937D01*
G01X143701Y114567D02*
X112205D01*
G01X143701D02*
G03X147638Y118504I0J3937D01*
G01X151575Y122441D02*
G03X147638Y118504I0J-3937D01*
G01X151575Y122441D02*
G03X147638Y118504I0J-3937D01*
G01X143701Y114567D02*
G03X147638Y118504I0J3937D01*
G01X222441Y122441D02*
X151575D01*
G01X143701Y106693D02*
X112205D01*
G01X119094Y177559D02*
G03X115157Y181496I-3937J0D01*
G01X119094Y177559D02*
Y165748D01*
G01X147638Y337796D02*
G03X151575Y333859I3937J0D01*
G01X147638Y337796D02*
G03X143701Y341733I-3937J0D01*
G01D02*
X112205D01*
G01X147638Y337796D02*
G03X151575Y333859I3937J0D01*
G01X147638Y337796D02*
G03X143701Y341733I-3937J0D01*
G01X147638Y337796D02*
G03X151575Y333859I3937J0D01*
G01X147638Y337796D02*
G03X143701Y341733I-3937J0D01*
G01X151575Y333859D02*
X222441D01*
G01X115157Y396851D02*
G03X119094Y400788I0J3937D01*
G01Y412599D02*
Y400788D01*
G01X151575Y357481D02*
G03X147638Y353544I0J-3937D01*
G01X143701Y349607D02*
G03X147638Y353544I0J3937D01*
G01X143701Y349607D02*
X112205D01*
G01X143701D02*
G03X147638Y353544I0J3937D01*
G01X151575Y357481D02*
G03X147638Y353544I0J-3937D01*
G01X151575Y357481D02*
G03X147638Y353544I0J-3937D01*
G01X143701Y349607D02*
G03X147638Y353544I0J3937D01*
G01X222441Y357481D02*
X151575D01*
G01X119094Y412599D02*
G03X115157Y416536I-3937J0D01*
G01X147638Y572835D02*
G03X151575Y568898I3937J0D01*
G01X147638Y572835D02*
G03X143701Y576772I-3937J0D01*
G01D02*
X112205D01*
G01X147638Y572835D02*
G03X151575Y568898I3937J0D01*
G01X147638Y572835D02*
G03X143701Y576772I-3937J0D01*
G01X147638Y572835D02*
G03X151575Y568898I3937J0D01*
G01X147638Y572835D02*
G03X143701Y576772I-3937J0D01*
G01X151575Y568898D02*
X222441D01*
G01X151575Y592520D02*
G03X147638Y588583I0J-3937D01*
G01X143701Y584646D02*
G03X147638Y588583I0J3937D01*
G01X143701Y584646D02*
X112205D01*
G01X143701D02*
G03X147638Y588583I0J3937D01*
G01X151575Y592520D02*
G03X147638Y588583I0J-3937D01*
G01X151575Y592520D02*
G03X147638Y588583I0J-3937D01*
G01X143701Y584646D02*
G03X147638Y588583I0J3937D01*
G01X119094Y647639D02*
G03X115157Y651576I-3937J0D01*
G01Y631891D02*
G03X119094Y635828I0J3937D01*
G01Y647639D02*
Y635828D01*
G01X222441Y592520D02*
X151575D01*
G01X222441Y98819D02*
G03X226378Y102756I0J3937D01*
G01X230315Y106693D02*
G03X226378Y102756I0J-3937D01*
G01X230315Y106693D02*
G03X226378Y102756I0J-3937D01*
G01X222441Y98819D02*
G03X226378Y102756I0J3937D01*
G01X222441Y98819D02*
G03X226378Y102756I0J3937D01*
G01X230315Y106693D02*
G03X226378Y102756I0J-3937D01*
G01Y118504D02*
G03X222441Y122441I-3937J0D01*
G01X226378Y118504D02*
G03X230315Y114567I3937J0D01*
G01D02*
X261811D01*
G01X226378Y118504D02*
G03X222441Y122441I-3937J0D01*
G01X226378Y118504D02*
G03X230315Y114567I3937J0D01*
G01X226378Y118504D02*
G03X222441Y122441I-3937J0D01*
G01X226378Y118504D02*
G03X230315Y114567I3937J0D01*
G01X370079D02*
X230315D01*
G01Y106693D02*
X261811D01*
G01X230315D02*
X370079D01*
G01X222441Y333859D02*
G03X226378Y337796I0J3937D01*
G01X230315Y341733D02*
G03X226378Y337796I0J-3937D01*
G01X230315Y341733D02*
X261811D01*
G01X230315D02*
G03X226378Y337796I0J-3937D01*
G01X222441Y333859D02*
G03X226378Y337796I0J3937D01*
G01X222441Y333859D02*
G03X226378Y337796I0J3937D01*
G01X230315Y341733D02*
G03X226378Y337796I0J-3937D01*
G01X230315Y341733D02*
X370079D01*
G01X226378Y353544D02*
G03X222441Y357481I-3937J0D01*
G01X226378Y353544D02*
G03X230315Y349607I3937J0D01*
G01D02*
X261811D01*
G01X226378Y353544D02*
G03X222441Y357481I-3937J0D01*
G01X226378Y353544D02*
G03X230315Y349607I3937J0D01*
G01X226378Y353544D02*
G03X222441Y357481I-3937J0D01*
G01X226378Y353544D02*
G03X230315Y349607I3937J0D01*
G01X370079D02*
X230315D01*
G01X222441Y568898D02*
G03X226378Y572835I0J3937D01*
G01X230315Y576772D02*
G03X226378Y572835I0J-3937D01*
G01X230315Y576772D02*
X261811D01*
G01X230315D02*
G03X226378Y572835I0J-3937D01*
G01X222441Y568898D02*
G03X226378Y572835I0J3937D01*
G01X222441Y568898D02*
G03X226378Y572835I0J3937D01*
G01X230315Y576772D02*
G03X226378Y572835I0J-3937D01*
G01X230315Y576772D02*
X370079D01*
G01X226378Y588583D02*
G03X222441Y592520I-3937J0D01*
G01X226378Y588583D02*
G03X230315Y584646I3937J0D01*
G01D02*
X261811D01*
G01X226378Y588583D02*
G03X222441Y592520I-3937J0D01*
G01X226378Y588583D02*
G03X230315Y584646I3937J0D01*
G01X226378Y588583D02*
G03X222441Y592520I-3937J0D01*
G01X226378Y588583D02*
G03X230315Y584646I3937J0D01*
G01X370079D02*
X230315D01*
G01X280906Y43701D02*
G03X284843Y39764I3937J0D01*
G01X270669D02*
G03X274606Y43701I0J3937D01*
G01X254921D02*
G03X258858Y39764I3937J0D01*
G01X270669D02*
X258858D01*
G01X296654D02*
X284843D01*
G01Y59449D02*
G03X280906Y55512I0J-3937D01*
G01X258858Y59449D02*
G03X254921Y55512I0J-3937D01*
G01X274606D02*
G03X270669Y59449I-3937J0D01*
G01X280906Y43701D02*
Y55512D01*
G01X274606D02*
Y43701D01*
G01X254921D02*
Y55512D01*
G01X284843Y59449D02*
X296654D01*
G01X258858D02*
X270669D01*
G01X284843Y106693D02*
G03Y114567I0J3937D01*
G01X280906Y278741D02*
G03X284843Y274804I3937J0D01*
G01X270669D02*
G03X274606Y278741I0J3937D01*
G01X254921D02*
G03X258858Y274804I3937J0D01*
G01X280906Y278741D02*
Y290552D01*
G01X274606D02*
Y278741D01*
G01X254921D02*
Y290552D01*
G01X270669Y274804D02*
X258858D01*
G01X296654D02*
X284843D01*
G01Y294489D02*
G03X280906Y290552I0J-3937D01*
G01X258858Y294489D02*
G03X254921Y290552I0J-3937D01*
G01X274606D02*
G03X270669Y294489I-3937J0D01*
G01X284843D02*
X296654D01*
G01X258858D02*
X270669D01*
G01X284843Y341733D02*
G03Y349607I0J3937D01*
G01X280906Y513780D02*
G03X284843Y509843I3937J0D01*
G01Y529528D02*
G03X280906Y525591I0J-3937D01*
G01X270669Y509843D02*
G03X274606Y513780I0J3937D01*
G01X254921D02*
G03X258858Y509843I3937J0D01*
G01Y529528D02*
G03X254921Y525591I0J-3937D01*
G01X274606D02*
G03X270669Y529528I-3937J0D01*
G01X280906Y513780D02*
Y525591D01*
G01X274606D02*
Y513780D01*
G01X254921D02*
Y525591D01*
G01X284843Y529528D02*
X296654D01*
G01X258858D02*
X270669D01*
G01Y509843D02*
X258858D01*
G01X296654D02*
X284843D01*
G01Y576772D02*
G03Y584646I0J3937D01*
G01X322638Y39764D02*
G03X326575Y43701I0J3937D01*
G01X306890D02*
G03X310827Y39764I3937J0D01*
G01X296654D02*
G03X300591Y43701I0J3937D01*
G01X322638Y39764D02*
X310827D01*
G01X308858Y29331D02*
G03X301378I-3740J0D01*
G01X350984Y0D02*
X352953Y1969D01*
G01X308858D02*
Y29331D01*
G01X299409Y0D02*
X301378Y1969D01*
G01D02*
Y29331D01*
G01X308858Y1969D02*
X310827Y0D01*
G01X350984D02*
X310827D01*
G01Y59449D02*
G03X306890Y55512I0J-3937D01*
G01X326575D02*
G03X322638Y59449I-3937J0D01*
G01X300591Y55512D02*
G03X296654Y59449I-3937J0D01*
G01X326575Y55512D02*
Y43701D01*
G01X306890D02*
Y55512D01*
G01X300591D02*
Y43701D01*
G01X310827Y59449D02*
X322638D01*
G01X315551Y114567D02*
G03Y106693I0J-3937D01*
G01X352953Y219292D02*
X350984Y221260D01*
G01X322638Y274804D02*
G03X326575Y278741I0J3937D01*
G01X306890D02*
G03X310827Y274804I3937J0D01*
G01X296654D02*
G03X300591Y278741I0J3937D01*
G01X326575Y290552D02*
Y278741D01*
G01X306890D02*
Y290552D01*
G01X300591D02*
Y278741D01*
G01X322638Y274804D02*
X310827D01*
G01X308858Y264370D02*
G03X301378I-3740J0D01*
G01X350984Y235040D02*
X352953Y237008D01*
G01X308858D02*
Y264370D01*
G01X299409Y235040D02*
X301378Y237008D01*
G01D02*
Y264370D01*
G01X308858Y237008D02*
X310827Y235040D01*
G01X350984D02*
X310827D01*
G01Y294489D02*
G03X306890Y290552I0J-3937D01*
G01X326575D02*
G03X322638Y294489I-3937J0D01*
G01X300591Y290552D02*
G03X296654Y294489I-3937J0D01*
G01X310827D02*
X322638D01*
G01X315551Y349607D02*
G03Y341733I0J-3937D01*
G01X352953Y454331D02*
X350984Y456300D01*
G01X322638Y509843D02*
G03X326575Y513780I0J3937D01*
G01X306890D02*
G03X310827Y509843I3937J0D01*
G01Y529528D02*
G03X306890Y525591I0J-3937D01*
G01X326575D02*
G03X322638Y529528I-3937J0D01*
G01X300591Y525591D02*
G03X296654Y529528I-3937J0D01*
G01Y509843D02*
G03X300591Y513780I0J3937D01*
G01X326575Y525591D02*
Y513780D01*
G01X306890D02*
Y525591D01*
G01X300591D02*
Y513780D01*
G01X310827Y529528D02*
X322638D01*
G01Y509843D02*
X310827D01*
G01X308858Y499410D02*
G03X301378I-3740J0D01*
G01X350984Y470079D02*
X352953Y472048D01*
G01X308858D02*
Y499410D01*
G01X299409Y470079D02*
X301378Y472048D01*
G01D02*
Y499410D01*
G01X308858Y472048D02*
X310827Y470079D01*
G01X350984D02*
X310827D01*
G01X315551Y584646D02*
G03Y576772I0J-3937D01*
G01X352953Y689371D02*
X350984Y691339D01*
G01X381890Y37795D02*
G03X385827Y33858I3937J0D01*
G01X402953Y29921D02*
G03X399016Y33858I-3937J0D01*
G01X385827D02*
X399016D01*
G01X681299Y0D02*
X404921D01*
G01X402953Y1969D02*
X404921Y0D01*
G01X402953Y1969D02*
Y29921D01*
G01X381890Y102756D02*
Y37795D01*
G01X352953Y1969D02*
Y59941D01*
G01D02*
Y33858D01*
G01X385827Y106693D02*
G03X381890Y102756I0J-3937D01*
G01X374016D02*
G03X370079Y106693I-3937J0D01*
G01Y63878D02*
G03X374016Y67815I0J3937D01*
G01X356890Y63878D02*
G03X352953Y59941I0J-3937D01*
G01X374016Y102756D02*
Y67815D01*
G01X370079Y63878D02*
X356890D01*
G01X374016Y98524D02*
G03X381890I3937J0D01*
G01Y67815D02*
G03X374016I-3937J0D01*
G01X385827Y106693D02*
X525591D01*
G01X370079Y114567D02*
G03X374016Y118504I0J3937D01*
G01D02*
Y183465D01*
G01X381890Y118504D02*
G03X385827Y114567I3937J0D01*
G01Y157382D02*
G03X381890Y153445I0J-3937D01*
G01X399016Y157382D02*
G03X402953Y161319I0J3937D01*
G01X381890Y118504D02*
Y153445D01*
G01X402953Y219292D02*
Y161319D01*
G01D02*
Y187402D01*
G01X525591Y114567D02*
X385827D01*
G01Y157382D02*
X399016D01*
G01X374016Y153445D02*
G03X381890I3937J0D01*
G01Y122737D02*
G03X374016I-3937J0D01*
G01Y183465D02*
G03X370079Y187402I-3937J0D01*
G01X352953Y191339D02*
G03X356890Y187402I3937J0D01*
G01X370079D02*
X356890D01*
G01X352953Y219292D02*
Y191339D01*
G01X404921Y221260D02*
X402953Y219292D01*
G01X404921Y221260D02*
X445079D01*
G01X352953Y237008D02*
Y294981D01*
G01D02*
Y268898D01*
G01X381890Y272835D02*
G03X385827Y268898I3937J0D01*
G01X402953Y264961D02*
G03X399016Y268898I-3937J0D01*
G01X385827D02*
X399016D01*
G01X681299Y235040D02*
X404921D01*
G01X402953Y237008D02*
X404921Y235040D01*
G01X402953Y237008D02*
Y264961D01*
G01X381890Y337796D02*
Y272835D01*
G01X374016Y337796D02*
G03X370079Y341733I-3937J0D01*
G01Y298918D02*
G03X374016Y302855I0J3937D01*
G01X356890Y298918D02*
G03X352953Y294981I0J-3937D01*
G01X374016Y337796D02*
Y302855D01*
G01X370079Y298918D02*
X356890D01*
G01X385827Y341733D02*
G03X381890Y337796I0J-3937D01*
G01X385827Y341733D02*
X525591D01*
G01X374016Y333563D02*
G03X381890I3937J0D01*
G01Y302855D02*
G03X374016I-3937J0D01*
G01X381890Y353544D02*
G03X385827Y349607I3937J0D01*
G01Y392422D02*
G03X381890Y388485I0J-3937D01*
G01X399016Y392422D02*
G03X402953Y396359I0J3937D01*
G01X381890Y353544D02*
Y388485D01*
G01X402953Y454331D02*
Y396359D01*
G01D02*
Y422441D01*
G01X525591Y349607D02*
X385827D01*
G01Y392422D02*
X399016D01*
G01X370079Y349607D02*
G03X374016Y353544I0J3937D01*
G01D02*
Y418504D01*
G01Y388485D02*
G03X381890I3937J0D01*
G01Y357776D02*
G03X374016I-3937J0D01*
G01X404921Y456300D02*
X402953Y454331D01*
G01X404921Y456300D02*
X445079D01*
G01X374016Y418504D02*
G03X370079Y422441I-3937J0D01*
G01X352953Y426378D02*
G03X356890Y422441I3937J0D01*
G01X370079D02*
X356890D01*
G01X352953Y454331D02*
Y426378D01*
G01Y472048D02*
Y530020D01*
G01D02*
Y503937D01*
G01X381890Y507874D02*
G03X385827Y503937I3937J0D01*
G01X402953Y500000D02*
G03X399016Y503937I-3937J0D01*
G01X385827D02*
X399016D01*
G01X681299Y470079D02*
X404921D01*
G01X402953Y472048D02*
X404921Y470079D01*
G01X402953Y472048D02*
Y500000D01*
G01X381890Y572835D02*
Y507874D01*
G01X374016Y572835D02*
G03X370079Y576772I-3937J0D01*
G01Y533957D02*
G03X374016Y537894I0J3937D01*
G01X356890Y533957D02*
G03X352953Y530020I0J-3937D01*
G01X374016Y572835D02*
Y537894D01*
G01X370079Y533957D02*
X356890D01*
G01X385827Y576772D02*
G03X381890Y572835I0J-3937D01*
G01X385827Y576772D02*
X525591D01*
G01X381890Y588583D02*
G03X385827Y584646I3937J0D01*
G01X381890Y588583D02*
Y623524D01*
G01X525591Y584646D02*
X385827D01*
G01X370079D02*
G03X374016Y588583I0J3937D01*
G01D02*
Y653544D01*
G01Y568603D02*
G03X381890I3937J0D01*
G01Y537894D02*
G03X374016I-3937J0D01*
G01X385827Y627461D02*
G03X381890Y623524I0J-3937D01*
G01X399016Y627461D02*
G03X402953Y631398I0J3937D01*
G01Y689371D02*
Y631398D01*
G01D02*
Y657481D01*
G01X385827Y627461D02*
X399016D01*
G01X374016Y623524D02*
G03X381890I3937J0D01*
G01Y592816D02*
G03X374016I-3937J0D01*
G01X404921Y691339D02*
X402953Y689371D01*
G01X404921Y691339D02*
X445079D01*
G01X374016Y653544D02*
G03X370079Y657481I-3937J0D01*
G01X352953Y661418D02*
G03X356890Y657481I3937J0D01*
G01X370079D02*
X356890D01*
G01X352953Y689371D02*
Y661418D01*
G01X445079Y161811D02*
G03X449016Y165748I0J3937D01*
G01X429331D02*
G03X433268Y161811I3937J0D01*
G01X455315Y165748D02*
G03X459252Y161811I3937J0D01*
G01X471063D02*
G03X475000Y165748I0J3937D01*
G01X445079Y161811D02*
X433268D01*
G01X471063D02*
X459252D01*
G01X471063Y114567D02*
G03Y106693I0J-3937D01*
G01X440354D02*
G03Y114567I0J3937D01*
G01X433268Y181496D02*
G03X429331Y177559I0J-3937D01*
G01X449016D02*
G03X445079Y181496I-3937J0D01*
G01X459252D02*
G03X455315Y177559I0J-3937D01*
G01X475000D02*
G03X471063Y181496I-3937J0D01*
G01X429331Y165748D02*
Y177559D01*
G01X449016D02*
Y165748D01*
G01X455315D02*
Y177559D01*
G01X459252Y181496D02*
X471063D01*
G01X433268D02*
X445079D01*
G01X447047Y191930D02*
G03X454528I3740J0D01*
G01X447047Y219292D02*
Y191930D01*
G01X456496Y221260D02*
X454528Y219292D01*
G01D02*
Y191930D01*
G01X447047Y219292D02*
X445079Y221260D01*
G01X456496D02*
X732874D01*
G01X471063Y349607D02*
G03Y341733I0J-3937D01*
G01X440354D02*
G03Y349607I0J3937D01*
G01X445079Y396851D02*
G03X449016Y400788I0J3937D01*
G01X429331D02*
G03X433268Y396851I3937J0D01*
G01X455315Y400788D02*
G03X459252Y396851I3937J0D01*
G01X471063D02*
G03X475000Y400788I0J3937D01*
G01X429331D02*
Y412599D01*
G01X449016D02*
Y400788D01*
G01X455315D02*
Y412599D01*
G01X445079Y396851D02*
X433268D01*
G01X471063D02*
X459252D01*
G01X433268Y416536D02*
G03X429331Y412599I0J-3937D01*
G01X449016D02*
G03X445079Y416536I-3937J0D01*
G01X459252D02*
G03X455315Y412599I0J-3937D01*
G01X475000D02*
G03X471063Y416536I-3937J0D01*
G01X459252D02*
X471063D01*
G01X433268D02*
X445079D01*
G01X447047Y426969D02*
G03X454528I3740J0D01*
G01X447047Y454331D02*
Y426969D01*
G01X456496Y456300D02*
X454528Y454331D01*
G01D02*
Y426969D01*
G01X447047Y454331D02*
X445079Y456300D01*
G01X456496D02*
X732874D01*
G01X471063Y584646D02*
G03Y576772I0J-3937D01*
G01X440354D02*
G03Y584646I0J3937D01*
G01X433268Y651576D02*
G03X429331Y647639I0J-3937D01*
G01X449016D02*
G03X445079Y651576I-3937J0D01*
G01Y631891D02*
G03X449016Y635828I0J3937D01*
G01X429331D02*
G03X433268Y631891I3937J0D01*
G01X455315Y635828D02*
G03X459252Y631891I3937J0D01*
G01Y651576D02*
G03X455315Y647639I0J-3937D01*
G01X475000D02*
G03X471063Y651576I-3937J0D01*
G01Y631891D02*
G03X475000Y635828I0J3937D01*
G01X429331D02*
Y647639D01*
G01X449016D02*
Y635828D01*
G01X455315D02*
Y647639D01*
G01X445079Y631891D02*
X433268D01*
G01X471063D02*
X459252D01*
G01Y651576D02*
X471063D01*
G01X433268D02*
X445079D01*
G01X447047Y662009D02*
G03X454528I3740J0D01*
G01X447047Y689371D02*
Y662009D01*
G01X456496Y691339D02*
X454528Y689371D01*
G01D02*
Y662009D01*
G01X447047Y689371D02*
X445079Y691339D01*
G01X456496D02*
X732874D01*
G01X529528Y102756D02*
G03X533465Y98819I3937J0D01*
G01X529528Y102756D02*
G03X525591Y106693I-3937J0D01*
G01X529528Y102756D02*
G03X533465Y98819I3937J0D01*
G01X529528Y102756D02*
G03X525591Y106693I-3937J0D01*
G01X529528Y102756D02*
G03X533465Y98819I3937J0D01*
G01X529528Y102756D02*
G03X525591Y106693I-3937J0D01*
G01X533465Y98819D02*
X604331D01*
G01X525591Y106693D02*
X494094D01*
G01X497047Y161811D02*
G03X500984Y165748I0J3937D01*
G01X481299D02*
G03X485236Y161811I3937J0D01*
G01X497047D02*
X485236D01*
G01X533465Y122441D02*
G03X529528Y118504I0J-3937D01*
G01X525591Y114567D02*
G03X529528Y118504I0J3937D01*
G01X525591Y114567D02*
X494094D01*
G01X525591D02*
G03X529528Y118504I0J3937D01*
G01X533465Y122441D02*
G03X529528Y118504I0J-3937D01*
G01X533465Y122441D02*
G03X529528Y118504I0J-3937D01*
G01X525591Y114567D02*
G03X529528Y118504I0J3937D01*
G01X604331Y122441D02*
X533465D01*
G01X485236Y181496D02*
G03X481299Y177559I0J-3937D01*
G01X500984D02*
G03X497047Y181496I-3937J0D01*
G01X475000Y177559D02*
Y165748D01*
G01X481299D02*
Y177559D01*
G01X500984D02*
Y165748D01*
G01X485236Y181496D02*
X497047D01*
G01X529528Y337796D02*
G03X533465Y333859I3937J0D01*
G01X529528Y337796D02*
G03X525591Y341733I-3937J0D01*
G01D02*
X494094D01*
G01X529528Y337796D02*
G03X533465Y333859I3937J0D01*
G01X529528Y337796D02*
G03X525591Y341733I-3937J0D01*
G01X529528Y337796D02*
G03X533465Y333859I3937J0D01*
G01X529528Y337796D02*
G03X525591Y341733I-3937J0D01*
G01X533465Y333859D02*
X604331D01*
G01X497047Y396851D02*
G03X500984Y400788I0J3937D01*
G01X481299D02*
G03X485236Y396851I3937J0D01*
G01X475000Y412599D02*
Y400788D01*
G01X481299D02*
Y412599D01*
G01X500984D02*
Y400788D01*
G01X497047Y396851D02*
X485236D01*
G01X533465Y357481D02*
G03X529528Y353544I0J-3937D01*
G01X525591Y349607D02*
G03X529528Y353544I0J3937D01*
G01X525591Y349607D02*
X494094D01*
G01X525591D02*
G03X529528Y353544I0J3937D01*
G01X533465Y357481D02*
G03X529528Y353544I0J-3937D01*
G01X533465Y357481D02*
G03X529528Y353544I0J-3937D01*
G01X525591Y349607D02*
G03X529528Y353544I0J3937D01*
G01X604331Y357481D02*
X533465D01*
G01X485236Y416536D02*
G03X481299Y412599I0J-3937D01*
G01X500984D02*
G03X497047Y416536I-3937J0D01*
G01X485236D02*
X497047D01*
G01X529528Y572835D02*
G03X533465Y568898I3937J0D01*
G01X529528Y572835D02*
G03X525591Y576772I-3937J0D01*
G01D02*
X494094D01*
G01X529528Y572835D02*
G03X533465Y568898I3937J0D01*
G01X529528Y572835D02*
G03X525591Y576772I-3937J0D01*
G01X529528Y572835D02*
G03X533465Y568898I3937J0D01*
G01X529528Y572835D02*
G03X525591Y576772I-3937J0D01*
G01X533465Y568898D02*
X604331D01*
G01X533465Y592520D02*
G03X529528Y588583I0J-3937D01*
G01X525591Y584646D02*
G03X529528Y588583I0J3937D01*
G01X525591Y584646D02*
X494094D01*
G01X525591D02*
G03X529528Y588583I0J3937D01*
G01X533465Y592520D02*
G03X529528Y588583I0J-3937D01*
G01X533465Y592520D02*
G03X529528Y588583I0J-3937D01*
G01X525591Y584646D02*
G03X529528Y588583I0J3937D01*
G01X485236Y651576D02*
G03X481299Y647639I0J-3937D01*
G01X500984D02*
G03X497047Y651576I-3937J0D01*
G01Y631891D02*
G03X500984Y635828I0J3937D01*
G01X481299D02*
G03X485236Y631891I3937J0D01*
G01X475000Y647639D02*
Y635828D01*
G01X481299D02*
Y647639D01*
G01X500984D02*
Y635828D01*
G01X497047Y631891D02*
X485236D01*
G01Y651576D02*
X497047D01*
G01X604331Y592520D02*
X533465D01*
G01X652559Y39764D02*
G03X656496Y43701I0J3937D01*
G01X636811D02*
G03X640748Y39764I3937J0D01*
G01X652559D02*
X640748D01*
G01Y59449D02*
G03X636811Y55512I0J-3937D01*
G01X656496D02*
G03X652559Y59449I-3937J0D01*
G01X656496Y55512D02*
Y43701D01*
G01X636811D02*
Y55512D01*
G01X640748Y59449D02*
X652559D01*
G01X604331Y98819D02*
G03X608268Y102756I0J3937D01*
G01X612205Y106693D02*
G03X608268Y102756I0J-3937D01*
G01X612205Y106693D02*
G03X608268Y102756I0J-3937D01*
G01X604331Y98819D02*
G03X608268Y102756I0J3937D01*
G01X604331Y98819D02*
G03X608268Y102756I0J3937D01*
G01X612205Y106693D02*
G03X608268Y102756I0J-3937D01*
G01X612205Y106693D02*
X643701D01*
G01X612205D02*
X751969D01*
G01X608268Y118504D02*
G03X604331Y122441I-3937J0D01*
G01X608268Y118504D02*
G03X612205Y114567I3937J0D01*
G01D02*
X643701D01*
G01X608268Y118504D02*
G03X604331Y122441I-3937J0D01*
G01X608268Y118504D02*
G03X612205Y114567I3937J0D01*
G01X608268Y118504D02*
G03X604331Y122441I-3937J0D01*
G01X608268Y118504D02*
G03X612205Y114567I3937J0D01*
G01X751969D02*
X612205D01*
G01X652559Y274804D02*
G03X656496Y278741I0J3937D01*
G01X636811D02*
G03X640748Y274804I3937J0D01*
G01X656496Y290552D02*
Y278741D01*
G01X636811D02*
Y290552D01*
G01X652559Y274804D02*
X640748D01*
G01Y294489D02*
G03X636811Y290552I0J-3937D01*
G01X656496D02*
G03X652559Y294489I-3937J0D01*
G01X640748D02*
X652559D01*
G01X604331Y333859D02*
G03X608268Y337796I0J3937D01*
G01X612205Y341733D02*
G03X608268Y337796I0J-3937D01*
G01X612205Y341733D02*
X643701D01*
G01X612205D02*
G03X608268Y337796I0J-3937D01*
G01X604331Y333859D02*
G03X608268Y337796I0J3937D01*
G01X604331Y333859D02*
G03X608268Y337796I0J3937D01*
G01X612205Y341733D02*
G03X608268Y337796I0J-3937D01*
G01X612205Y341733D02*
X751969D01*
G01X608268Y353544D02*
G03X604331Y357481I-3937J0D01*
G01X608268Y353544D02*
G03X612205Y349607I3937J0D01*
G01D02*
X643701D01*
G01X608268Y353544D02*
G03X604331Y357481I-3937J0D01*
G01X608268Y353544D02*
G03X612205Y349607I3937J0D01*
G01X608268Y353544D02*
G03X604331Y357481I-3937J0D01*
G01X608268Y353544D02*
G03X612205Y349607I3937J0D01*
G01X751969D02*
X612205D01*
G01X652559Y509843D02*
G03X656496Y513780I0J3937D01*
G01X636811D02*
G03X640748Y509843I3937J0D01*
G01Y529528D02*
G03X636811Y525591I0J-3937D01*
G01X656496D02*
G03X652559Y529528I-3937J0D01*
G01X656496Y525591D02*
Y513780D01*
G01X636811D02*
Y525591D01*
G01X640748Y529528D02*
X652559D01*
G01Y509843D02*
X640748D01*
G01X604331Y568898D02*
G03X608268Y572835I0J3937D01*
G01X612205Y576772D02*
G03X608268Y572835I0J-3937D01*
G01X612205Y576772D02*
X643701D01*
G01X612205D02*
G03X608268Y572835I0J-3937D01*
G01X604331Y568898D02*
G03X608268Y572835I0J3937D01*
G01X604331Y568898D02*
G03X608268Y572835I0J3937D01*
G01X612205Y576772D02*
G03X608268Y572835I0J-3937D01*
G01X612205Y576772D02*
X751969D01*
G01X608268Y588583D02*
G03X604331Y592520I-3937J0D01*
G01X608268Y588583D02*
G03X612205Y584646I3937J0D01*
G01D02*
X643701D01*
G01X608268Y588583D02*
G03X604331Y592520I-3937J0D01*
G01X608268Y588583D02*
G03X612205Y584646I3937J0D01*
G01X608268Y588583D02*
G03X604331Y592520I-3937J0D01*
G01X608268Y588583D02*
G03X612205Y584646I3937J0D01*
G01X751969D02*
X612205D01*
G01X704528Y39764D02*
G03X708465Y43701I0J3937D01*
G01X688780D02*
G03X692717Y39764I3937J0D01*
G01X678543D02*
G03X682480Y43701I0J3937D01*
G01X662795D02*
G03X666732Y39764I3937J0D01*
G01X678543D02*
X666732D01*
G01X704528D02*
X692717D01*
G01X690748Y29331D02*
G03X683268I-3740J0D01*
G01X690748Y1969D02*
Y29331D01*
G01X681299Y0D02*
X683268Y1969D01*
G01D02*
Y29331D01*
G01X690748Y1969D02*
X692717Y0D01*
G01X732874D02*
X692717D01*
G01Y59449D02*
G03X688780Y55512I0J-3937D01*
G01X708465D02*
G03X704528Y59449I-3937J0D01*
G01X682480Y55512D02*
G03X678543Y59449I-3937J0D01*
G01X666732D02*
G03X662795Y55512I0J-3937D01*
G01X708465D02*
Y43701D01*
G01X688780D02*
Y55512D01*
G01X682480D02*
Y43701D01*
G01X662795D02*
Y55512D01*
G01X692717Y59449D02*
X704528D01*
G01X666732D02*
X678543D01*
G01X697441Y114567D02*
G03Y106693I0J-3937D01*
G01X666732D02*
G03Y114567I0J3937D01*
G01X704528Y274804D02*
G03X708465Y278741I0J3937D01*
G01X688780D02*
G03X692717Y274804I3937J0D01*
G01X678543D02*
G03X682480Y278741I0J3937D01*
G01X662795D02*
G03X666732Y274804I3937J0D01*
G01X708465Y290552D02*
Y278741D01*
G01X688780D02*
Y290552D01*
G01X682480D02*
Y278741D01*
G01X662795D02*
Y290552D01*
G01X678543Y274804D02*
X666732D01*
G01X704528D02*
X692717D01*
G01X690748Y264370D02*
G03X683268I-3740J0D01*
G01X690748Y237008D02*
Y264370D01*
G01X681299Y235040D02*
X683268Y237008D01*
G01D02*
Y264370D01*
G01X690748Y237008D02*
X692717Y235040D01*
G01X732874D02*
X692717D01*
G01Y294489D02*
G03X688780Y290552I0J-3937D01*
G01X708465D02*
G03X704528Y294489I-3937J0D01*
G01X682480Y290552D02*
G03X678543Y294489I-3937J0D01*
G01X666732D02*
G03X662795Y290552I0J-3937D01*
G01X692717Y294489D02*
X704528D01*
G01X666732D02*
X678543D01*
G01X697441Y349607D02*
G03Y341733I0J-3937D01*
G01X666732D02*
G03Y349607I0J3937D01*
G01X704528Y509843D02*
G03X708465Y513780I0J3937D01*
G01X688780D02*
G03X692717Y509843I3937J0D01*
G01Y529528D02*
G03X688780Y525591I0J-3937D01*
G01X708465D02*
G03X704528Y529528I-3937J0D01*
G01X682480Y525591D02*
G03X678543Y529528I-3937J0D01*
G01Y509843D02*
G03X682480Y513780I0J3937D01*
G01X662795D02*
G03X666732Y509843I3937J0D01*
G01Y529528D02*
G03X662795Y525591I0J-3937D01*
G01X708465D02*
Y513780D01*
G01X688780D02*
Y525591D01*
G01X682480D02*
Y513780D01*
G01X662795D02*
Y525591D01*
G01X692717Y529528D02*
X704528D01*
G01X666732D02*
X678543D01*
G01Y509843D02*
X666732D01*
G01X704528D02*
X692717D01*
G01X690748Y499410D02*
G03X683268I-3740J0D01*
G01X690748Y472048D02*
Y499410D01*
G01X681299Y470079D02*
X683268Y472048D01*
G01D02*
Y499410D01*
G01X690748Y472048D02*
X692717Y470079D01*
G01X732874D02*
X692717D01*
G01X697441Y584646D02*
G03Y576772I0J-3937D01*
G01X666732D02*
G03Y584646I0J3937D01*
G01X734843Y1969D02*
Y59941D01*
G01D02*
Y33858D01*
G01X732874Y0D02*
X734843Y1969D01*
G01X762744Y17317D02*
G03I-4292J0D01*
G01X775591Y553149D02*
Y15000D01*
G01X760591Y0D02*
G03X775591Y15000I0J15000D01*
G01X742717Y0D02*
Y56004D01*
G01Y0D02*
X760591D01*
G01X755906Y102756D02*
G03X751969Y106693I-3937J0D01*
G01Y63878D02*
G03X755906Y67815I0J3937D01*
G01X738780Y63878D02*
G03X734843Y59941I0J-3937D01*
G01X755906Y102756D02*
Y67815D01*
G01X751969Y63878D02*
X738780D01*
G01X763780Y152761D02*
Y98517D01*
G01Y67822D02*
Y67803D01*
G01X751969Y56004D02*
X742717D01*
G01X751969D02*
G03X763780Y67815I0J11811D01*
G01D02*
G03X755906I-3937J0D01*
G01Y98524D02*
G03X763780I3937J0D01*
G01X751969Y114567D02*
G03X755906Y118504I0J3937D01*
G01D02*
Y183465D01*
G01X763780Y152756D02*
G03X755906I-3937J0D01*
G01Y183465D02*
G03X751969Y187402I-3937J0D01*
G01X734843Y191339D02*
G03X738780Y187402I3937J0D01*
G01X751969D02*
X738780D01*
G01X734843Y219292D02*
X732874Y221260D01*
G01X734843Y219292D02*
Y191339D01*
G01X755906Y183465D02*
G03X763780I3937J0D01*
G01Y302855D02*
Y183460D01*
G01X734843Y237008D02*
Y294981D01*
G01D02*
Y268898D01*
G01X732874Y235040D02*
X734843Y237008D01*
G01X755906Y337796D02*
G03X751969Y341733I-3937J0D01*
G01Y298918D02*
G03X755906Y302855I0J3937D01*
G01X738780Y298918D02*
G03X734843Y294981I0J-3937D01*
G01X755906Y337796D02*
Y302855D01*
G01X751969Y298918D02*
X738780D01*
G01X763780Y387796D02*
Y333559D01*
G01Y302855D02*
G03X755906I-3937J0D01*
G01Y333563D02*
G03X763780I3937J0D01*
G01X751969Y349607D02*
G03X755906Y353544I0J3937D01*
G01D02*
Y418504D01*
G01X763780Y387796D02*
G03X755906I-3937J0D01*
G01Y418504D02*
G03X751969Y422441I-3937J0D01*
G01X734843Y426378D02*
G03X738780Y422441I3937J0D01*
G01X751969D02*
X738780D01*
G01X734843Y454331D02*
X732874Y456300D01*
G01X734843Y454331D02*
Y426378D01*
G01X763780Y537894D02*
Y418504D01*
G01X755906Y418505D02*
G03X763780I3937J0D01*
G01X734843Y472048D02*
Y530020D01*
G01D02*
Y503937D01*
G01X732874Y470079D02*
X734843Y472048D01*
G01X755906Y572835D02*
G03X751969Y576772I-3937J0D01*
G01Y533957D02*
G03X755906Y537894I0J3937D01*
G01X738780Y533957D02*
G03X734843Y530020I0J-3937D01*
G01X755906Y572835D02*
Y537894D01*
G01X751969Y533957D02*
X738780D01*
G01X751969Y584646D02*
G03X755906Y588583I0J3937D01*
G01D02*
Y653544D01*
G01X775591Y561023D02*
G03Y553149I0J-3937D01*
G01X763780Y537894D02*
G03X755906I-3937J0D01*
G01Y568603D02*
G03X763780I3937J0D01*
G01X775591Y676339D02*
Y561023D01*
G01X763780Y622835D02*
Y568603D01*
G01Y622835D02*
G03X755906I-3937J0D01*
G01Y653544D02*
G03X763780I3937J0D01*
G01X755906D02*
G03X751969Y657481I-3937J0D01*
G01X734843Y661418D02*
G03X738780Y657481I3937J0D01*
G01X751969D02*
X738780D01*
G01X734843Y689371D02*
X732874Y691339D01*
G01X734843Y689371D02*
Y661418D01*
G01X760014Y677788D02*
G03I-4292J0D01*
G01X775591Y676339D02*
G03X760591Y691339I-15000J0D01*
G01X751969Y665355D02*
X742717D01*
G01X763780Y653544D02*
G03X751969Y665355I-11811J0D01*
G01X742717Y691339D02*
X760591D01*
G01X742717Y665355D02*
Y691339D01*
G54D12*
G01X182396Y64257D02*
Y23920D01*
G01D02*
X181102Y22626D01*
G01D02*
Y13762D01*
G01X181103Y65551D02*
Y65550D01*
G01D02*
X182396Y64257D01*
G01X331233Y38100D02*
Y60800D01*
G01X326772Y33639D02*
X331233Y38100D01*
G01X326772Y13762D02*
Y33639D01*
G01X312733Y33900D02*
Y24700D01*
G01D02*
X311024Y22991D01*
G01D02*
Y13762D01*
G01X305633Y59300D02*
Y41000D01*
G01D02*
X312733Y33900D01*
G01X329233Y59700D02*
Y39700D01*
G01D02*
X318898Y29365D01*
G01D02*
Y13762D01*
G01X328233Y59200D02*
Y40400D01*
G01D02*
X314961Y27128D01*
G01D02*
Y13762D01*
G01X350394Y15712D02*
Y29994D01*
G01D02*
X350396Y29996D01*
G01D02*
Y35224D01*
G01D02*
X348650Y36970D01*
G01D02*
Y62760D01*
G01X333090Y27360D02*
Y63320D01*
G01X334646Y25804D02*
X333090Y27360D01*
G01X334646Y13762D02*
Y25804D01*
G01X330233Y60200D02*
Y38800D01*
G01D02*
X322835Y31402D01*
G01D02*
Y13762D01*
G01X330709D02*
Y25719D01*
G01D02*
X332158Y27168D01*
G01D02*
Y64100D01*
G01X331233Y60800D02*
X326772Y65261D01*
G01D02*
Y73426D01*
G01D02*
X326773D01*
G01X311023D02*
X311022D01*
G01D02*
X308953Y71357D01*
G01D02*
Y62620D01*
G01D02*
X305633Y59300D01*
G01X318898Y73426D02*
X318897D01*
G01D02*
Y64164D01*
G01D02*
X320436Y62625D01*
G01D02*
X326308D01*
G01D02*
X329233Y59700D01*
G01X314963Y65551D02*
Y65550D01*
G01D02*
X318813Y61700D01*
G01D02*
X325733D01*
G01D02*
X328233Y59200D01*
G01X348650Y62760D02*
X350393Y64503D01*
G01D02*
Y73426D01*
G01X333720Y72498D02*
X334648Y73426D01*
G01X333720Y63950D02*
Y72498D01*
G01X333090Y63320D02*
X333720Y63950D01*
G01X322833Y65551D02*
X324882D01*
G01D02*
X330233Y60200D01*
G01X330708Y65550D02*
Y65551D01*
G01X332158Y64100D02*
X330708Y65550D01*
M02*
